(kicad_sch
	(version 20250114)
	(generator "eeschema")
	(generator_version "9.0")
	(paper "A3")
	(title_block
		(title "Antmicro Baseboard for Jetson AGX Thor")
		(date "2026-02-17")
		(rev "1.1.0")
		(company "Antmicro Ltd")
		(comment 1 "www.antmicro.com")
	)
	(text "3V3@1A"
		(exclude_from_sim no)
		(at 138.43 77.724 0)
		(effects
			(font
				(size 1.27 1.27)
			)
			(justify left bottom)
		)
	)
	(text "Overvoltage set to 25.4V"
		(exclude_from_sim no)
		(at 277.114 70.104 0)
		(effects
			(font
				(size 1.27 1.27)
			)
		)
	)
	(text "USB PD Power Ideal Diodes"
		(exclude_from_sim no)
		(at 340.36 16.256 0)
		(effects
			(font
				(size 2.54 2.54)
				(thickness 0.4)
				(bold yes)
			)
			(justify left)
		)
	)
	(text "Power LEDs and testpoints"
		(exclude_from_sim no)
		(at 266.192 162.306 0)
		(effects
			(font
				(size 2.54 2.54)
				(thickness 0.4)
				(bold yes)
			)
			(justify left)
		)
	)
	(text "Power sequencing"
		(exclude_from_sim no)
		(at 68.453 162.433 0)
		(effects
			(font
				(size 2.54 2.54)
				(thickness 0.4)
				(bold yes)
			)
			(justify left)
		)
	)
	(text "V_{OUT} = 0.8*(1+31.6k/10k) = 3.328[V]"
		(exclude_from_sim no)
		(at 59.944 101.6 0)
		(effects
			(font
				(size 1.27 1.27)
			)
			(justify left bottom)
		)
	)
	(text "V_{OUT} = 0.8*(1+R_{1}/R_{2})\n"
		(exclude_from_sim no)
		(at 59.944 99.06 0)
		(effects
			(font
				(size 1.27 1.27)
			)
			(justify left bottom)
		)
	)
	(text "Input selector"
		(exclude_from_sim no)
		(at 244.348 16.002 0)
		(effects
			(font
				(size 2.54 2.54)
				(thickness 0.4)
				(bold yes)
			)
			(justify left)
		)
	)
	(text "UP TO 20A"
		(exclude_from_sim no)
		(at 226.568 35.052 0)
		(effects
			(font
				(size 1.27 1.27)
			)
			(justify left bottom)
		)
	)
	(text "24VDC"
		(exclude_from_sim no)
		(at 197.104 27.178 0)
		(effects
			(font
				(size 1.27 1.27)
			)
			(justify left bottom)
		)
	)
	(text "3V3 standby LDO"
		(exclude_from_sim no)
		(at 76.2 62.23 0)
		(effects
			(font
				(size 2.54 2.54)
				(thickness 0.4)
				(bold yes)
			)
			(justify left)
		)
	)
	(junction
		(at 110.49 81.28)
		(diameter 0)
		(color 0 0 0 0)
	)
	(junction
		(at 290.83 200.66)
		(diameter 0)
		(color 0 0 0 0)
	)
	(junction
		(at 290.83 35.56)
		(diameter 0)
		(color 0 0 0 0)
	)
	(junction
		(at 351.79 107.95)
		(diameter 0)
		(color 0 0 0 0)
	)
	(junction
		(at 368.3 210.82)
		(diameter 0)
		(color 0 0 0 0)
	)
	(junction
		(at 308.61 135.89)
		(diameter 0)
		(color 0 0 0 0)
	)
	(junction
		(at 193.04 38.1)
		(diameter 0)
		(color 0 0 0 0)
	)
	(junction
		(at 248.92 190.5)
		(diameter 0)
		(color 0 0 0 0)
	)
	(junction
		(at 265.43 35.56)
		(diameter 0)
		(color 0 0 0 0)
	)
	(junction
		(at 259.08 193.04)
		(diameter 0)
		(color 0 0 0 0)
	)
	(junction
		(at 193.04 35.56)
		(diameter 0)
		(color 0 0 0 0)
	)
	(junction
		(at 342.9 57.15)
		(diameter 0)
		(color 0 0 0 0)
	)
	(junction
		(at 130.81 81.28)
		(diameter 0)
		(color 0 0 0 0)
	)
	(junction
		(at 351.79 93.98)
		(diameter 0)
		(color 0 0 0 0)
	)
	(junction
		(at 275.59 35.56)
		(diameter 0)
		(color 0 0 0 0)
	)
	(junction
		(at 193.04 40.64)
		(diameter 0)
		(color 0 0 0 0)
	)
	(junction
		(at 308.61 99.06)
		(diameter 0)
		(color 0 0 0 0)
	)
	(junction
		(at 276.86 99.06)
		(diameter 0)
		(color 0 0 0 0)
	)
	(junction
		(at 281.94 106.68)
		(diameter 0)
		(color 0 0 0 0)
	)
	(junction
		(at 294.64 57.15)
		(diameter 0)
		(color 0 0 0 0)
	)
	(junction
		(at 214.63 35.56)
		(diameter 0)
		(color 0 0 0 0)
	)
	(junction
		(at 276.86 85.09)
		(diameter 0)
		(color 0 0 0 0)
	)
	(junction
		(at 219.71 35.56)
		(diameter 0)
		(color 0 0 0 0)
	)
	(junction
		(at 218.44 185.42)
		(diameter 0)
		(color 0 0 0 0)
	)
	(junction
		(at 279.4 198.12)
		(diameter 0)
		(color 0 0 0 0)
	)
	(junction
		(at 356.87 113.03)
		(diameter 0)
		(color 0 0 0 0)
	)
	(junction
		(at 276.86 121.92)
		(diameter 0)
		(color 0 0 0 0)
	)
	(junction
		(at 287.02 85.09)
		(diameter 0)
		(color 0 0 0 0)
	)
	(junction
		(at 383.54 99.06)
		(diameter 0)
		(color 0 0 0 0)
	)
	(junction
		(at 101.6 88.9)
		(diameter 0)
		(color 0 0 0 0)
	)
	(junction
		(at 288.29 121.92)
		(diameter 0)
		(color 0 0 0 0)
	)
	(junction
		(at 383.54 62.23)
		(diameter 0)
		(color 0 0 0 0)
	)
	(junction
		(at 308.61 121.92)
		(diameter 0)
		(color 0 0 0 0)
	)
	(junction
		(at 383.54 71.12)
		(diameter 0)
		(color 0 0 0 0)
	)
	(junction
		(at 351.79 71.12)
		(diameter 0)
		(color 0 0 0 0)
	)
	(junction
		(at 316.23 35.56)
		(diameter 0)
		(color 0 0 0 0)
	)
	(junction
		(at 356.87 78.74)
		(diameter 0)
		(color 0 0 0 0)
	)
	(junction
		(at 208.28 38.1)
		(diameter 0)
		(color 0 0 0 0)
	)
	(junction
		(at 127 81.28)
		(diameter 0)
		(color 0 0 0 0)
	)
	(junction
		(at 60.96 81.28)
		(diameter 0)
		(color 0 0 0 0)
	)
	(junction
		(at 281.94 104.14)
		(diameter 0)
		(color 0 0 0 0)
	)
	(junction
		(at 224.79 35.56)
		(diameter 0)
		(color 0 0 0 0)
	)
	(junction
		(at 300.99 203.2)
		(diameter 0)
		(color 0 0 0 0)
	)
	(junction
		(at 208.28 182.88)
		(diameter 0)
		(color 0 0 0 0)
	)
	(junction
		(at 281.94 143.51)
		(diameter 0)
		(color 0 0 0 0)
	)
	(junction
		(at 308.61 85.09)
		(diameter 0)
		(color 0 0 0 0)
	)
	(junction
		(at 101.6 81.28)
		(diameter 0)
		(color 0 0 0 0)
	)
	(junction
		(at 262.89 59.69)
		(diameter 0)
		(color 0 0 0 0)
	)
	(junction
		(at 269.24 195.58)
		(diameter 0)
		(color 0 0 0 0)
	)
	(junction
		(at 265.43 62.23)
		(diameter 0)
		(color 0 0 0 0)
	)
	(junction
		(at 356.87 76.2)
		(diameter 0)
		(color 0 0 0 0)
	)
	(junction
		(at 317.5 85.09)
		(diameter 0)
		(color 0 0 0 0)
	)
	(junction
		(at 356.87 115.57)
		(diameter 0)
		(color 0 0 0 0)
	)
	(junction
		(at 351.79 57.15)
		(diameter 0)
		(color 0 0 0 0)
	)
	(junction
		(at 238.76 35.56)
		(diameter 0)
		(color 0 0 0 0)
	)
	(junction
		(at 336.55 210.82)
		(diameter 0)
		(color 0 0 0 0)
	)
	(junction
		(at 383.54 93.98)
		(diameter 0)
		(color 0 0 0 0)
	)
	(junction
		(at 280.67 35.56)
		(diameter 0)
		(color 0 0 0 0)
	)
	(junction
		(at 208.28 35.56)
		(diameter 0)
		(color 0 0 0 0)
	)
	(junction
		(at 314.96 35.56)
		(diameter 0)
		(color 0 0 0 0)
	)
	(junction
		(at 383.54 57.15)
		(diameter 0)
		(color 0 0 0 0)
	)
	(junction
		(at 280.67 41.91)
		(diameter 0)
		(color 0 0 0 0)
	)
	(junction
		(at 260.35 35.56)
		(diameter 0)
		(color 0 0 0 0)
	)
	(junction
		(at 238.76 190.5)
		(diameter 0)
		(color 0 0 0 0)
	)
	(junction
		(at 72.39 81.28)
		(diameter 0)
		(color 0 0 0 0)
	)
	(junction
		(at 228.6 187.96)
		(diameter 0)
		(color 0 0 0 0)
	)
	(junction
		(at 281.94 140.97)
		(diameter 0)
		(color 0 0 0 0)
	)
	(junction
		(at 276.86 135.89)
		(diameter 0)
		(color 0 0 0 0)
	)
	(junction
		(at 383.54 107.95)
		(diameter 0)
		(color 0 0 0 0)
	)
	(junction
		(at 273.05 35.56)
		(diameter 0)
		(color 0 0 0 0)
	)
	(junction
		(at 265.43 57.15)
		(diameter 0)
		(color 0 0 0 0)
	)
	(no_connect
		(at 377.19 113.03)
	)
	(no_connect
		(at 377.19 76.2)
	)
	(no_connect
		(at 302.26 104.14)
	)
	(no_connect
		(at 302.26 140.97)
	)
	(no_connect
		(at 90.17 83.82)
	)
	(wire
		(pts
			(xy 279.4 181.61) (xy 279.4 198.12)
		)
		(stroke
			(width 0)
			(type default)
		)
	)
	(wire
		(pts
			(xy 317.5 208.28) (xy 313.69 208.28)
		)
		(stroke
			(width 0)
			(type default)
		)
	)
	(wire
		(pts
			(xy 351.79 57.15) (xy 370.84 57.15)
		)
		(stroke
			(width 0)
			(type default)
		)
	)
	(wire
		(pts
			(xy 281.94 138.43) (xy 284.48 138.43)
		)
		(stroke
			(width 0)
			(type default)
		)
	)
	(wire
		(pts
			(xy 110.49 81.28) (xy 116.84 81.28)
		)
		(stroke
			(width 0)
			(type default)
		)
	)
	(wire
		(pts
			(xy 260.35 50.8) (xy 260.35 35.56)
		)
		(stroke
			(width 0)
			(type default)
		)
	)
	(wire
		(pts
			(xy 351.79 93.98) (xy 351.79 107.95)
		)
		(stroke
			(width 0)
			(type default)
		)
	)
	(wire
		(pts
			(xy 306.07 85.09) (xy 308.61 85.09)
		)
		(stroke
			(width 0)
			(type default)
		)
	)
	(wire
		(pts
			(xy 351.79 114.3) (xy 351.79 115.57)
		)
		(stroke
			(width 0)
			(type default)
		)
	)
	(wire
		(pts
			(xy 248.92 190.5) (xy 317.5 190.5)
		)
		(stroke
			(width 0)
			(type default)
		)
	)
	(wire
		(pts
			(xy 288.29 41.91) (xy 288.29 59.69)
		)
		(stroke
			(width 0)
			(type default)
		)
	)
	(wire
		(pts
			(xy 208.28 215.9) (xy 208.28 217.17)
		)
		(stroke
			(width 0)
			(type default)
		)
	)
	(wire
		(pts
			(xy 195.58 35.56) (xy 193.04 35.56)
		)
		(stroke
			(width 0)
			(type default)
		)
	)
	(wire
		(pts
			(xy 273.05 34.29) (xy 273.05 35.56)
		)
		(stroke
			(width 0)
			(type default)
		)
	)
	(wire
		(pts
			(xy 60.96 87.63) (xy 60.96 88.9)
		)
		(stroke
			(width 0)
			(type default)
		)
	)
	(wire
		(pts
			(xy 356.87 76.2) (xy 359.41 76.2)
		)
		(stroke
			(width 0)
			(type default)
		)
	)
	(polyline
		(pts
			(xy 180.34 13.97) (xy 180.34 284.48)
		)
		(stroke
			(width 0)
			(type default)
		)
	)
	(wire
		(pts
			(xy 205.74 40.64) (xy 208.28 40.64)
		)
		(stroke
			(width 0)
			(type default)
		)
	)
	(wire
		(pts
			(xy 208.28 182.88) (xy 208.28 204.47)
		)
		(stroke
			(width 0)
			(type default)
		)
	)
	(wire
		(pts
			(xy 265.43 57.15) (xy 265.43 62.23)
		)
		(stroke
			(width 0)
			(type default)
		)
	)
	(wire
		(pts
			(xy 74.93 86.36) (xy 72.39 86.36)
		)
		(stroke
			(width 0)
			(type default)
		)
	)
	(wire
		(pts
			(xy 345.44 213.36) (xy 345.44 218.44)
		)
		(stroke
			(width 0)
			(type default)
		)
	)
	(wire
		(pts
			(xy 287.02 85.09) (xy 295.91 85.09)
		)
		(stroke
			(width 0)
			(type default)
		)
	)
	(wire
		(pts
			(xy 196.85 185.42) (xy 218.44 185.42)
		)
		(stroke
			(width 0)
			(type default)
		)
	)
	(wire
		(pts
			(xy 309.88 35.56) (xy 314.96 35.56)
		)
		(stroke
			(width 0)
			(type default)
		)
	)
	(wire
		(pts
			(xy 208.28 181.61) (xy 208.28 182.88)
		)
		(stroke
			(width 0)
			(type default)
		)
	)
	(wire
		(pts
			(xy 101.6 87.63) (xy 101.6 88.9)
		)
		(stroke
			(width 0)
			(type default)
		)
	)
	(wire
		(pts
			(xy 248.92 190.5) (xy 248.92 204.47)
		)
		(stroke
			(width 0)
			(type default)
		)
	)
	(wire
		(pts
			(xy 224.79 35.56) (xy 238.76 35.56)
		)
		(stroke
			(width 0)
			(type default)
		)
	)
	(wire
		(pts
			(xy 303.53 128.27) (xy 303.53 138.43)
		)
		(stroke
			(width 0)
			(type default)
		)
	)
	(wire
		(pts
			(xy 130.81 80.01) (xy 130.81 81.28)
		)
		(stroke
			(width 0)
			(type default)
		)
	)
	(wire
		(pts
			(xy 290.83 35.56) (xy 299.72 35.56)
		)
		(stroke
			(width 0)
			(type default)
		)
	)
	(wire
		(pts
			(xy 377.19 213.36) (xy 377.19 218.44)
		)
		(stroke
			(width 0)
			(type default)
		)
	)
	(wire
		(pts
			(xy 290.83 34.29) (xy 290.83 35.56)
		)
		(stroke
			(width 0)
			(type default)
		)
	)
	(wire
		(pts
			(xy 251.46 41.91) (xy 262.89 41.91)
		)
		(stroke
			(width 0)
			(type default)
		)
	)
	(wire
		(pts
			(xy 276.86 83.82) (xy 276.86 85.09)
		)
		(stroke
			(width 0)
			(type default)
		)
	)
	(polyline
		(pts
			(xy 330.2 11.938) (xy 330.2 152.4)
		)
		(stroke
			(width 0)
			(type default)
		)
	)
	(wire
		(pts
			(xy 265.43 35.56) (xy 273.05 35.56)
		)
		(stroke
			(width 0)
			(type default)
		)
	)
	(wire
		(pts
			(xy 313.69 208.28) (xy 313.69 217.17)
		)
		(stroke
			(width 0)
			(type default)
		)
	)
	(wire
		(pts
			(xy 351.79 93.98) (xy 342.9 93.98)
		)
		(stroke
			(width 0)
			(type default)
		)
	)
	(wire
		(pts
			(xy 276.86 143.51) (xy 281.94 143.51)
		)
		(stroke
			(width 0)
			(type default)
		)
	)
	(wire
		(pts
			(xy 60.96 81.28) (xy 60.96 82.55)
		)
		(stroke
			(width 0)
			(type default)
		)
	)
	(wire
		(pts
			(xy 269.24 215.9) (xy 269.24 217.17)
		)
		(stroke
			(width 0)
			(type default)
		)
	)
	(wire
		(pts
			(xy 273.05 35.56) (xy 275.59 35.56)
		)
		(stroke
			(width 0)
			(type default)
		)
	)
	(wire
		(pts
			(xy 248.92 215.9) (xy 248.92 217.17)
		)
		(stroke
			(width 0)
			(type default)
		)
	)
	(wire
		(pts
			(xy 127 82.55) (xy 127 81.28)
		)
		(stroke
			(width 0)
			(type default)
		)
	)
	(wire
		(pts
			(xy 302.26 99.06) (xy 308.61 99.06)
		)
		(stroke
			(width 0)
			(type default)
		)
	)
	(wire
		(pts
			(xy 308.61 85.09) (xy 317.5 85.09)
		)
		(stroke
			(width 0)
			(type default)
		)
	)
	(wire
		(pts
			(xy 269.24 209.55) (xy 269.24 210.82)
		)
		(stroke
			(width 0)
			(type default)
		)
	)
	(wire
		(pts
			(xy 218.44 185.42) (xy 317.5 185.42)
		)
		(stroke
			(width 0)
			(type default)
		)
	)
	(wire
		(pts
			(xy 356.87 110.49) (xy 356.87 113.03)
		)
		(stroke
			(width 0)
			(type default)
		)
	)
	(wire
		(pts
			(xy 276.86 85.09) (xy 287.02 85.09)
		)
		(stroke
			(width 0)
			(type default)
		)
	)
	(wire
		(pts
			(xy 218.44 185.42) (xy 218.44 204.47)
		)
		(stroke
			(width 0)
			(type default)
		)
	)
	(wire
		(pts
			(xy 251.46 59.69) (xy 251.46 57.15)
		)
		(stroke
			(width 0)
			(type default)
		)
	)
	(wire
		(pts
			(xy 383.54 99.06) (xy 383.54 107.95)
		)
		(stroke
			(width 0)
			(type default)
		)
	)
	(wire
		(pts
			(xy 303.53 91.44) (xy 303.53 101.6)
		)
		(stroke
			(width 0)
			(type default)
		)
	)
	(wire
		(pts
			(xy 228.6 181.61) (xy 228.6 187.96)
		)
		(stroke
			(width 0)
			(type default)
		)
	)
	(wire
		(pts
			(xy 276.86 105.41) (xy 276.86 106.68)
		)
		(stroke
			(width 0)
			(type default)
		)
	)
	(wire
		(pts
			(xy 196.85 193.04) (xy 259.08 193.04)
		)
		(stroke
			(width 0)
			(type default)
		)
	)
	(wire
		(pts
			(xy 281.94 106.68) (xy 281.94 107.95)
		)
		(stroke
			(width 0)
			(type default)
		)
	)
	(wire
		(pts
			(xy 294.64 41.91) (xy 294.64 57.15)
		)
		(stroke
			(width 0)
			(type default)
		)
	)
	(wire
		(pts
			(xy 288.29 121.92) (xy 295.91 121.92)
		)
		(stroke
			(width 0)
			(type default)
		)
	)
	(wire
		(pts
			(xy 269.24 181.61) (xy 269.24 195.58)
		)
		(stroke
			(width 0)
			(type default)
		)
	)
	(wire
		(pts
			(xy 193.04 40.64) (xy 193.04 43.18)
		)
		(stroke
			(width 0)
			(type default)
		)
	)
	(wire
		(pts
			(xy 377.19 189.23) (xy 377.19 190.5)
		)
		(stroke
			(width 0)
			(type default)
		)
	)
	(wire
		(pts
			(xy 335.28 210.82) (xy 336.55 210.82)
		)
		(stroke
			(width 0)
			(type default)
		)
	)
	(wire
		(pts
			(xy 208.28 209.55) (xy 208.28 210.82)
		)
		(stroke
			(width 0)
			(type default)
		)
	)
	(wire
		(pts
			(xy 281.94 140.97) (xy 281.94 143.51)
		)
		(stroke
			(width 0)
			(type default)
		)
	)
	(wire
		(pts
			(xy 336.55 217.17) (xy 336.55 218.44)
		)
		(stroke
			(width 0)
			(type default)
		)
	)
	(wire
		(pts
			(xy 336.55 207.01) (xy 336.55 210.82)
		)
		(stroke
			(width 0)
			(type default)
		)
	)
	(wire
		(pts
			(xy 317.5 85.09) (xy 317.5 121.92)
		)
		(stroke
			(width 0)
			(type default)
		)
	)
	(wire
		(pts
			(xy 290.83 181.61) (xy 290.83 200.66)
		)
		(stroke
			(width 0)
			(type default)
		)
	)
	(wire
		(pts
			(xy 279.4 215.9) (xy 279.4 217.17)
		)
		(stroke
			(width 0)
			(type default)
		)
	)
	(wire
		(pts
			(xy 195.58 40.64) (xy 193.04 40.64)
		)
		(stroke
			(width 0)
			(type default)
		)
	)
	(wire
		(pts
			(xy 127 81.28) (xy 130.81 81.28)
		)
		(stroke
			(width 0)
			(type default)
		)
	)
	(wire
		(pts
			(xy 273.05 85.09) (xy 276.86 85.09)
		)
		(stroke
			(width 0)
			(type default)
		)
	)
	(wire
		(pts
			(xy 195.58 38.1) (xy 193.04 38.1)
		)
		(stroke
			(width 0)
			(type default)
		)
	)
	(wire
		(pts
			(xy 205.74 35.56) (xy 208.28 35.56)
		)
		(stroke
			(width 0)
			(type default)
		)
	)
	(wire
		(pts
			(xy 276.86 106.68) (xy 281.94 106.68)
		)
		(stroke
			(width 0)
			(type default)
		)
	)
	(wire
		(pts
			(xy 196.85 208.28) (xy 200.66 208.28)
		)
		(stroke
			(width 0)
			(type default)
		)
	)
	(wire
		(pts
			(xy 356.87 113.03) (xy 356.87 115.57)
		)
		(stroke
			(width 0)
			(type default)
		)
	)
	(wire
		(pts
			(xy 237.49 62.23) (xy 265.43 62.23)
		)
		(stroke
			(width 0)
			(type default)
		)
	)
	(wire
		(pts
			(xy 290.83 200.66) (xy 290.83 204.47)
		)
		(stroke
			(width 0)
			(type default)
		)
	)
	(wire
		(pts
			(xy 300.99 209.55) (xy 300.99 210.82)
		)
		(stroke
			(width 0)
			(type default)
		)
	)
	(wire
		(pts
			(xy 196.85 190.5) (xy 238.76 190.5)
		)
		(stroke
			(width 0)
			(type default)
		)
	)
	(wire
		(pts
			(xy 356.87 113.03) (xy 359.41 113.03)
		)
		(stroke
			(width 0)
			(type default)
		)
	)
	(wire
		(pts
			(xy 351.79 57.15) (xy 351.79 71.12)
		)
		(stroke
			(width 0)
			(type default)
		)
	)
	(wire
		(pts
			(xy 218.44 209.55) (xy 218.44 210.82)
		)
		(stroke
			(width 0)
			(type default)
		)
	)
	(wire
		(pts
			(xy 306.07 121.92) (xy 308.61 121.92)
		)
		(stroke
			(width 0)
			(type default)
		)
	)
	(wire
		(pts
			(xy 377.19 107.95) (xy 383.54 107.95)
		)
		(stroke
			(width 0)
			(type default)
		)
	)
	(wire
		(pts
			(xy 300.99 181.61) (xy 300.99 203.2)
		)
		(stroke
			(width 0)
			(type default)
		)
	)
	(wire
		(pts
			(xy 132.08 81.28) (xy 130.81 81.28)
		)
		(stroke
			(width 0)
			(type default)
		)
	)
	(wire
		(pts
			(xy 377.19 195.58) (xy 377.19 196.85)
		)
		(stroke
			(width 0)
			(type default)
		)
	)
	(wire
		(pts
			(xy 351.79 57.15) (xy 342.9 57.15)
		)
		(stroke
			(width 0)
			(type default)
		)
	)
	(wire
		(pts
			(xy 284.48 57.15) (xy 294.64 57.15)
		)
		(stroke
			(width 0)
			(type default)
		)
	)
	(wire
		(pts
			(xy 214.63 34.29) (xy 214.63 35.56)
		)
		(stroke
			(width 0)
			(type default)
		)
	)
	(wire
		(pts
			(xy 383.54 62.23) (xy 384.81 62.23)
		)
		(stroke
			(width 0)
			(type default)
		)
	)
	(wire
		(pts
			(xy 238.76 35.56) (xy 243.84 35.56)
		)
		(stroke
			(width 0)
			(type default)
		)
	)
	(wire
		(pts
			(xy 90.17 86.36) (xy 92.71 86.36)
		)
		(stroke
			(width 0)
			(type default)
		)
	)
	(wire
		(pts
			(xy 101.6 81.28) (xy 101.6 82.55)
		)
		(stroke
			(width 0)
			(type default)
		)
	)
	(wire
		(pts
			(xy 276.86 120.65) (xy 276.86 121.92)
		)
		(stroke
			(width 0)
			(type default)
		)
	)
	(wire
		(pts
			(xy 368.3 210.82) (xy 368.3 212.09)
		)
		(stroke
			(width 0)
			(type default)
		)
	)
	(wire
		(pts
			(xy 196.85 182.88) (xy 208.28 182.88)
		)
		(stroke
			(width 0)
			(type default)
		)
	)
	(wire
		(pts
			(xy 276.86 121.92) (xy 288.29 121.92)
		)
		(stroke
			(width 0)
			(type default)
		)
	)
	(wire
		(pts
			(xy 316.23 35.56) (xy 322.58 35.56)
		)
		(stroke
			(width 0)
			(type default)
		)
	)
	(wire
		(pts
			(xy 356.87 78.74) (xy 356.87 80.01)
		)
		(stroke
			(width 0)
			(type default)
		)
	)
	(wire
		(pts
			(xy 196.85 198.12) (xy 279.4 198.12)
		)
		(stroke
			(width 0)
			(type default)
		)
	)
	(wire
		(pts
			(xy 218.44 181.61) (xy 218.44 185.42)
		)
		(stroke
			(width 0)
			(type default)
		)
	)
	(wire
		(pts
			(xy 377.19 110.49) (xy 378.46 110.49)
		)
		(stroke
			(width 0)
			(type default)
		)
	)
	(wire
		(pts
			(xy 238.76 215.9) (xy 238.76 217.17)
		)
		(stroke
			(width 0)
			(type default)
		)
	)
	(wire
		(pts
			(xy 351.79 93.98) (xy 370.84 93.98)
		)
		(stroke
			(width 0)
			(type default)
		)
	)
	(wire
		(pts
			(xy 218.44 215.9) (xy 218.44 217.17)
		)
		(stroke
			(width 0)
			(type default)
		)
	)
	(wire
		(pts
			(xy 193.04 35.56) (xy 193.04 38.1)
		)
		(stroke
			(width 0)
			(type default)
		)
	)
	(wire
		(pts
			(xy 377.19 73.66) (xy 378.46 73.66)
		)
		(stroke
			(width 0)
			(type default)
		)
	)
	(wire
		(pts
			(xy 275.59 35.56) (xy 280.67 35.56)
		)
		(stroke
			(width 0)
			(type default)
		)
	)
	(wire
		(pts
			(xy 260.35 35.56) (xy 265.43 35.56)
		)
		(stroke
			(width 0)
			(type default)
		)
	)
	(wire
		(pts
			(xy 351.79 77.47) (xy 351.79 78.74)
		)
		(stroke
			(width 0)
			(type default)
		)
	)
	(wire
		(pts
			(xy 383.54 93.98) (xy 387.35 93.98)
		)
		(stroke
			(width 0)
			(type default)
		)
	)
	(wire
		(pts
			(xy 336.55 210.82) (xy 339.09 210.82)
		)
		(stroke
			(width 0)
			(type default)
		)
	)
	(wire
		(pts
			(xy 290.83 200.66) (xy 317.5 200.66)
		)
		(stroke
			(width 0)
			(type default)
		)
	)
	(wire
		(pts
			(xy 300.99 204.47) (xy 300.99 203.2)
		)
		(stroke
			(width 0)
			(type default)
		)
	)
	(wire
		(pts
			(xy 60.96 78.74) (xy 60.96 81.28)
		)
		(stroke
			(width 0)
			(type default)
		)
	)
	(wire
		(pts
			(xy 356.87 110.49) (xy 359.41 110.49)
		)
		(stroke
			(width 0)
			(type default)
		)
	)
	(wire
		(pts
			(xy 290.83 215.9) (xy 290.83 217.17)
		)
		(stroke
			(width 0)
			(type default)
		)
	)
	(wire
		(pts
			(xy 345.44 201.93) (xy 345.44 203.2)
		)
		(stroke
			(width 0)
			(type default)
		)
	)
	(wire
		(pts
			(xy 193.04 38.1) (xy 193.04 40.64)
		)
		(stroke
			(width 0)
			(type default)
		)
	)
	(wire
		(pts
			(xy 281.94 138.43) (xy 281.94 140.97)
		)
		(stroke
			(width 0)
			(type default)
		)
	)
	(wire
		(pts
			(xy 378.46 100.33) (xy 378.46 110.49)
		)
		(stroke
			(width 0)
			(type default)
		)
	)
	(wire
		(pts
			(xy 280.67 35.56) (xy 280.67 36.83)
		)
		(stroke
			(width 0)
			(type default)
		)
	)
	(wire
		(pts
			(xy 308.61 99.06) (xy 308.61 102.87)
		)
		(stroke
			(width 0)
			(type default)
		)
	)
	(wire
		(pts
			(xy 92.71 86.36) (xy 92.71 88.9)
		)
		(stroke
			(width 0)
			(type default)
		)
	)
	(wire
		(pts
			(xy 279.4 198.12) (xy 279.4 204.47)
		)
		(stroke
			(width 0)
			(type default)
		)
	)
	(wire
		(pts
			(xy 302.26 138.43) (xy 303.53 138.43)
		)
		(stroke
			(width 0)
			(type default)
		)
	)
	(wire
		(pts
			(xy 317.5 203.2) (xy 300.99 203.2)
		)
		(stroke
			(width 0)
			(type default)
		)
	)
	(wire
		(pts
			(xy 368.3 207.01) (xy 368.3 210.82)
		)
		(stroke
			(width 0)
			(type default)
		)
	)
	(wire
		(pts
			(xy 351.79 115.57) (xy 356.87 115.57)
		)
		(stroke
			(width 0)
			(type default)
		)
	)
	(wire
		(pts
			(xy 90.17 81.28) (xy 101.6 81.28)
		)
		(stroke
			(width 0)
			(type default)
		)
	)
	(wire
		(pts
			(xy 308.61 85.09) (xy 308.61 99.06)
		)
		(stroke
			(width 0)
			(type default)
		)
	)
	(wire
		(pts
			(xy 205.74 38.1) (xy 208.28 38.1)
		)
		(stroke
			(width 0)
			(type default)
		)
	)
	(wire
		(pts
			(xy 276.86 135.89) (xy 276.86 137.16)
		)
		(stroke
			(width 0)
			(type default)
		)
	)
	(wire
		(pts
			(xy 224.79 34.29) (xy 224.79 35.56)
		)
		(stroke
			(width 0)
			(type default)
		)
	)
	(wire
		(pts
			(xy 284.48 59.69) (xy 288.29 59.69)
		)
		(stroke
			(width 0)
			(type default)
		)
	)
	(wire
		(pts
			(xy 110.49 87.63) (xy 110.49 88.9)
		)
		(stroke
			(width 0)
			(type default)
		)
	)
	(wire
		(pts
			(xy 336.55 210.82) (xy 336.55 212.09)
		)
		(stroke
			(width 0)
			(type default)
		)
	)
	(wire
		(pts
			(xy 300.99 217.17) (xy 300.99 215.9)
		)
		(stroke
			(width 0)
			(type default)
		)
	)
	(wire
		(pts
			(xy 121.92 81.28) (xy 127 81.28)
		)
		(stroke
			(width 0)
			(type default)
		)
	)
	(wire
		(pts
			(xy 279.4 198.12) (xy 317.5 198.12)
		)
		(stroke
			(width 0)
			(type default)
		)
	)
	(wire
		(pts
			(xy 302.26 135.89) (xy 308.61 135.89)
		)
		(stroke
			(width 0)
			(type default)
		)
	)
	(wire
		(pts
			(xy 281.94 104.14) (xy 281.94 106.68)
		)
		(stroke
			(width 0)
			(type default)
		)
	)
	(wire
		(pts
			(xy 281.94 143.51) (xy 281.94 144.78)
		)
		(stroke
			(width 0)
			(type default)
		)
	)
	(wire
		(pts
			(xy 367.03 210.82) (xy 368.3 210.82)
		)
		(stroke
			(width 0)
			(type default)
		)
	)
	(wire
		(pts
			(xy 368.3 210.82) (xy 370.84 210.82)
		)
		(stroke
			(width 0)
			(type default)
		)
	)
	(wire
		(pts
			(xy 265.43 57.15) (xy 266.7 57.15)
		)
		(stroke
			(width 0)
			(type default)
		)
	)
	(wire
		(pts
			(xy 383.54 99.06) (xy 384.81 99.06)
		)
		(stroke
			(width 0)
			(type default)
		)
	)
	(wire
		(pts
			(xy 262.89 59.69) (xy 266.7 59.69)
		)
		(stroke
			(width 0)
			(type default)
		)
	)
	(wire
		(pts
			(xy 381 93.98) (xy 383.54 93.98)
		)
		(stroke
			(width 0)
			(type default)
		)
	)
	(wire
		(pts
			(xy 383.54 62.23) (xy 383.54 71.12)
		)
		(stroke
			(width 0)
			(type default)
		)
	)
	(wire
		(pts
			(xy 238.76 190.5) (xy 238.76 204.47)
		)
		(stroke
			(width 0)
			(type default)
		)
	)
	(wire
		(pts
			(xy 290.83 209.55) (xy 290.83 210.82)
		)
		(stroke
			(width 0)
			(type default)
		)
	)
	(wire
		(pts
			(xy 281.94 101.6) (xy 281.94 104.14)
		)
		(stroke
			(width 0)
			(type default)
		)
	)
	(wire
		(pts
			(xy 208.28 40.64) (xy 208.28 38.1)
		)
		(stroke
			(width 0)
			(type default)
		)
	)
	(wire
		(pts
			(xy 356.87 115.57) (xy 356.87 116.84)
		)
		(stroke
			(width 0)
			(type default)
		)
	)
	(wire
		(pts
			(xy 259.08 209.55) (xy 259.08 210.82)
		)
		(stroke
			(width 0)
			(type default)
		)
	)
	(wire
		(pts
			(xy 259.08 215.9) (xy 259.08 217.17)
		)
		(stroke
			(width 0)
			(type default)
		)
	)
	(wire
		(pts
			(xy 214.63 35.56) (xy 219.71 35.56)
		)
		(stroke
			(width 0)
			(type default)
		)
	)
	(wire
		(pts
			(xy 269.24 195.58) (xy 269.24 204.47)
		)
		(stroke
			(width 0)
			(type default)
		)
	)
	(wire
		(pts
			(xy 254 35.56) (xy 260.35 35.56)
		)
		(stroke
			(width 0)
			(type default)
		)
	)
	(wire
		(pts
			(xy 276.86 121.92) (xy 273.05 121.92)
		)
		(stroke
			(width 0)
			(type default)
		)
	)
	(wire
		(pts
			(xy 248.92 209.55) (xy 248.92 210.82)
		)
		(stroke
			(width 0)
			(type default)
		)
	)
	(wire
		(pts
			(xy 351.79 71.12) (xy 359.41 71.12)
		)
		(stroke
			(width 0)
			(type default)
		)
	)
	(wire
		(pts
			(xy 72.39 81.28) (xy 74.93 81.28)
		)
		(stroke
			(width 0)
			(type default)
		)
	)
	(wire
		(pts
			(xy 308.61 121.92) (xy 308.61 135.89)
		)
		(stroke
			(width 0)
			(type default)
		)
	)
	(wire
		(pts
			(xy 269.24 195.58) (xy 317.5 195.58)
		)
		(stroke
			(width 0)
			(type default)
		)
	)
	(wire
		(pts
			(xy 60.96 81.28) (xy 72.39 81.28)
		)
		(stroke
			(width 0)
			(type default)
		)
	)
	(wire
		(pts
			(xy 383.54 57.15) (xy 383.54 62.23)
		)
		(stroke
			(width 0)
			(type default)
		)
	)
	(wire
		(pts
			(xy 378.46 63.5) (xy 378.46 73.66)
		)
		(stroke
			(width 0)
			(type default)
		)
	)
	(wire
		(pts
			(xy 314.96 35.56) (xy 314.96 50.8)
		)
		(stroke
			(width 0)
			(type default)
		)
	)
	(wire
		(pts
			(xy 196.85 187.96) (xy 228.6 187.96)
		)
		(stroke
			(width 0)
			(type default)
		)
	)
	(wire
		(pts
			(xy 275.59 35.56) (xy 275.59 39.37)
		)
		(stroke
			(width 0)
			(type default)
		)
	)
	(wire
		(pts
			(xy 238.76 181.61) (xy 238.76 190.5)
		)
		(stroke
			(width 0)
			(type default)
		)
	)
	(wire
		(pts
			(xy 356.87 73.66) (xy 359.41 73.66)
		)
		(stroke
			(width 0)
			(type default)
		)
	)
	(wire
		(pts
			(xy 265.43 35.56) (xy 265.43 57.15)
		)
		(stroke
			(width 0)
			(type default)
		)
	)
	(wire
		(pts
			(xy 219.71 35.56) (xy 219.71 36.83)
		)
		(stroke
			(width 0)
			(type default)
		)
	)
	(wire
		(pts
			(xy 356.87 76.2) (xy 356.87 78.74)
		)
		(stroke
			(width 0)
			(type default)
		)
	)
	(wire
		(pts
			(xy 72.39 86.36) (xy 72.39 88.9)
		)
		(stroke
			(width 0)
			(type default)
		)
	)
	(wire
		(pts
			(xy 262.89 41.91) (xy 262.89 59.69)
		)
		(stroke
			(width 0)
			(type default)
		)
	)
	(wire
		(pts
			(xy 314.96 50.8) (xy 309.88 50.8)
		)
		(stroke
			(width 0)
			(type default)
		)
	)
	(wire
		(pts
			(xy 345.44 189.23) (xy 345.44 190.5)
		)
		(stroke
			(width 0)
			(type default)
		)
	)
	(wire
		(pts
			(xy 238.76 209.55) (xy 238.76 210.82)
		)
		(stroke
			(width 0)
			(type default)
		)
	)
	(wire
		(pts
			(xy 219.71 35.56) (xy 224.79 35.56)
		)
		(stroke
			(width 0)
			(type default)
		)
	)
	(wire
		(pts
			(xy 285.75 62.23) (xy 285.75 63.5)
		)
		(stroke
			(width 0)
			(type default)
		)
	)
	(wire
		(pts
			(xy 238.76 50.8) (xy 243.84 50.8)
		)
		(stroke
			(width 0)
			(type default)
		)
	)
	(wire
		(pts
			(xy 284.48 62.23) (xy 285.75 62.23)
		)
		(stroke
			(width 0)
			(type default)
		)
	)
	(wire
		(pts
			(xy 276.86 99.06) (xy 284.48 99.06)
		)
		(stroke
			(width 0)
			(type default)
		)
	)
	(wire
		(pts
			(xy 200.66 208.28) (xy 200.66 217.17)
		)
		(stroke
			(width 0)
			(type default)
		)
	)
	(wire
		(pts
			(xy 281.94 140.97) (xy 284.48 140.97)
		)
		(stroke
			(width 0)
			(type default)
		)
	)
	(wire
		(pts
			(xy 302.26 41.91) (xy 294.64 41.91)
		)
		(stroke
			(width 0)
			(type default)
		)
	)
	(wire
		(pts
			(xy 101.6 88.9) (xy 101.6 90.17)
		)
		(stroke
			(width 0)
			(type default)
		)
	)
	(wire
		(pts
			(xy 314.96 35.56) (xy 316.23 35.56)
		)
		(stroke
			(width 0)
			(type default)
		)
	)
	(wire
		(pts
			(xy 101.6 88.9) (xy 92.71 88.9)
		)
		(stroke
			(width 0)
			(type default)
		)
	)
	(wire
		(pts
			(xy 208.28 38.1) (xy 208.28 35.56)
		)
		(stroke
			(width 0)
			(type default)
		)
	)
	(wire
		(pts
			(xy 308.61 121.92) (xy 317.5 121.92)
		)
		(stroke
			(width 0)
			(type default)
		)
	)
	(wire
		(pts
			(xy 280.67 35.56) (xy 290.83 35.56)
		)
		(stroke
			(width 0)
			(type default)
		)
	)
	(wire
		(pts
			(xy 265.43 62.23) (xy 266.7 62.23)
		)
		(stroke
			(width 0)
			(type default)
		)
	)
	(wire
		(pts
			(xy 276.86 85.09) (xy 276.86 99.06)
		)
		(stroke
			(width 0)
			(type default)
		)
	)
	(wire
		(pts
			(xy 342.9 57.15) (xy 342.9 93.98)
		)
		(stroke
			(width 0)
			(type default)
		)
	)
	(wire
		(pts
			(xy 387.35 57.15) (xy 383.54 57.15)
		)
		(stroke
			(width 0)
			(type default)
		)
	)
	(wire
		(pts
			(xy 238.76 190.5) (xy 248.92 190.5)
		)
		(stroke
			(width 0)
			(type default)
		)
	)
	(wire
		(pts
			(xy 74.93 83.82) (xy 72.39 83.82)
		)
		(stroke
			(width 0)
			(type default)
		)
	)
	(wire
		(pts
			(xy 101.6 95.25) (xy 101.6 96.52)
		)
		(stroke
			(width 0)
			(type default)
		)
	)
	(wire
		(pts
			(xy 281.94 104.14) (xy 284.48 104.14)
		)
		(stroke
			(width 0)
			(type default)
		)
	)
	(wire
		(pts
			(xy 276.86 99.06) (xy 276.86 100.33)
		)
		(stroke
			(width 0)
			(type default)
		)
	)
	(wire
		(pts
			(xy 345.44 195.58) (xy 345.44 196.85)
		)
		(stroke
			(width 0)
			(type default)
		)
	)
	(wire
		(pts
			(xy 351.79 107.95) (xy 351.79 109.22)
		)
		(stroke
			(width 0)
			(type default)
		)
	)
	(wire
		(pts
			(xy 356.87 73.66) (xy 356.87 76.2)
		)
		(stroke
			(width 0)
			(type default)
		)
	)
	(wire
		(pts
			(xy 377.19 71.12) (xy 383.54 71.12)
		)
		(stroke
			(width 0)
			(type default)
		)
	)
	(wire
		(pts
			(xy 351.79 71.12) (xy 351.79 72.39)
		)
		(stroke
			(width 0)
			(type default)
		)
	)
	(wire
		(pts
			(xy 228.6 187.96) (xy 228.6 204.47)
		)
		(stroke
			(width 0)
			(type default)
		)
	)
	(wire
		(pts
			(xy 325.12 85.09) (xy 317.5 85.09)
		)
		(stroke
			(width 0)
			(type default)
		)
	)
	(wire
		(pts
			(xy 351.79 107.95) (xy 359.41 107.95)
		)
		(stroke
			(width 0)
			(type default)
		)
	)
	(wire
		(pts
			(xy 259.08 193.04) (xy 317.5 193.04)
		)
		(stroke
			(width 0)
			(type default)
		)
	)
	(wire
		(pts
			(xy 208.28 35.56) (xy 214.63 35.56)
		)
		(stroke
			(width 0)
			(type default)
		)
	)
	(wire
		(pts
			(xy 276.86 135.89) (xy 284.48 135.89)
		)
		(stroke
			(width 0)
			(type default)
		)
	)
	(wire
		(pts
			(xy 383.54 71.12) (xy 383.54 74.93)
		)
		(stroke
			(width 0)
			(type default)
		)
	)
	(wire
		(pts
			(xy 196.85 200.66) (xy 290.83 200.66)
		)
		(stroke
			(width 0)
			(type default)
		)
	)
	(wire
		(pts
			(xy 276.86 142.24) (xy 276.86 143.51)
		)
		(stroke
			(width 0)
			(type default)
		)
	)
	(wire
		(pts
			(xy 193.04 34.29) (xy 193.04 35.56)
		)
		(stroke
			(width 0)
			(type default)
		)
	)
	(wire
		(pts
			(xy 308.61 135.89) (xy 308.61 139.7)
		)
		(stroke
			(width 0)
			(type default)
		)
	)
	(wire
		(pts
			(xy 299.72 50.8) (xy 290.83 50.8)
		)
		(stroke
			(width 0)
			(type default)
		)
	)
	(wire
		(pts
			(xy 127 87.63) (xy 127 88.9)
		)
		(stroke
			(width 0)
			(type default)
		)
	)
	(wire
		(pts
			(xy 302.26 101.6) (xy 303.53 101.6)
		)
		(stroke
			(width 0)
			(type default)
		)
	)
	(wire
		(pts
			(xy 280.67 41.91) (xy 280.67 43.18)
		)
		(stroke
			(width 0)
			(type default)
		)
	)
	(wire
		(pts
			(xy 290.83 50.8) (xy 290.83 35.56)
		)
		(stroke
			(width 0)
			(type default)
		)
	)
	(wire
		(pts
			(xy 101.6 81.28) (xy 110.49 81.28)
		)
		(stroke
			(width 0)
			(type default)
		)
	)
	(wire
		(pts
			(xy 238.76 35.56) (xy 238.76 50.8)
		)
		(stroke
			(width 0)
			(type default)
		)
	)
	(wire
		(pts
			(xy 208.28 182.88) (xy 317.5 182.88)
		)
		(stroke
			(width 0)
			(type default)
		)
	)
	(wire
		(pts
			(xy 288.29 41.91) (xy 280.67 41.91)
		)
		(stroke
			(width 0)
			(type default)
		)
	)
	(wire
		(pts
			(xy 368.3 217.17) (xy 368.3 218.44)
		)
		(stroke
			(width 0)
			(type default)
		)
	)
	(wire
		(pts
			(xy 351.79 78.74) (xy 356.87 78.74)
		)
		(stroke
			(width 0)
			(type default)
		)
	)
	(wire
		(pts
			(xy 228.6 209.55) (xy 228.6 210.82)
		)
		(stroke
			(width 0)
			(type default)
		)
	)
	(wire
		(pts
			(xy 228.6 215.9) (xy 228.6 217.17)
		)
		(stroke
			(width 0)
			(type default)
		)
	)
	(polyline
		(pts
			(xy 12.7 152.4) (xy 407.67 152.4)
		)
		(stroke
			(width 0)
			(type default)
		)
	)
	(wire
		(pts
			(xy 110.49 81.28) (xy 110.49 82.55)
		)
		(stroke
			(width 0)
			(type default)
		)
	)
	(wire
		(pts
			(xy 72.39 81.28) (xy 72.39 83.82)
		)
		(stroke
			(width 0)
			(type default)
		)
	)
	(wire
		(pts
			(xy 276.86 121.92) (xy 276.86 135.89)
		)
		(stroke
			(width 0)
			(type default)
		)
	)
	(wire
		(pts
			(xy 228.6 187.96) (xy 317.5 187.96)
		)
		(stroke
			(width 0)
			(type default)
		)
	)
	(wire
		(pts
			(xy 279.4 209.55) (xy 279.4 210.82)
		)
		(stroke
			(width 0)
			(type default)
		)
	)
	(wire
		(pts
			(xy 377.19 201.93) (xy 377.19 203.2)
		)
		(stroke
			(width 0)
			(type default)
		)
	)
	(wire
		(pts
			(xy 381 57.15) (xy 383.54 57.15)
		)
		(stroke
			(width 0)
			(type default)
		)
	)
	(wire
		(pts
			(xy 294.64 57.15) (xy 302.26 57.15)
		)
		(stroke
			(width 0)
			(type default)
		)
	)
	(wire
		(pts
			(xy 219.71 41.91) (xy 219.71 43.18)
		)
		(stroke
			(width 0)
			(type default)
		)
	)
	(wire
		(pts
			(xy 196.85 203.2) (xy 300.99 203.2)
		)
		(stroke
			(width 0)
			(type default)
		)
	)
	(wire
		(pts
			(xy 383.54 93.98) (xy 383.54 99.06)
		)
		(stroke
			(width 0)
			(type default)
		)
	)
	(wire
		(pts
			(xy 342.9 52.07) (xy 342.9 57.15)
		)
		(stroke
			(width 0)
			(type default)
		)
	)
	(wire
		(pts
			(xy 259.08 193.04) (xy 259.08 204.47)
		)
		(stroke
			(width 0)
			(type default)
		)
	)
	(wire
		(pts
			(xy 281.94 101.6) (xy 284.48 101.6)
		)
		(stroke
			(width 0)
			(type default)
		)
	)
	(wire
		(pts
			(xy 259.08 181.61) (xy 259.08 193.04)
		)
		(stroke
			(width 0)
			(type default)
		)
	)
	(wire
		(pts
			(xy 251.46 59.69) (xy 262.89 59.69)
		)
		(stroke
			(width 0)
			(type default)
		)
	)
	(wire
		(pts
			(xy 383.54 107.95) (xy 383.54 111.76)
		)
		(stroke
			(width 0)
			(type default)
		)
	)
	(wire
		(pts
			(xy 196.85 195.58) (xy 269.24 195.58)
		)
		(stroke
			(width 0)
			(type default)
		)
	)
	(wire
		(pts
			(xy 254 50.8) (xy 260.35 50.8)
		)
		(stroke
			(width 0)
			(type default)
		)
	)
	(table
		(column_count 4)
		(border
			(external yes)
			(header yes)
			(stroke
				(width 0)
				(type solid)
			)
		)
		(separators
			(rows yes)
			(cols yes)
			(stroke
				(width 0)
				(type solid)
			)
		)
		(column_widths 22.86 22.86 22.86 22.86)
		(row_heights 5.08 5.08 5.08 5.08 5.08 5.08 5.08 5.08 5.08 5.08 5.08)
		(cells
			(table_cell "Sequence"
				(exclude_from_sim no)
				(at 19.685 169.545 0)
				(size 22.86 5.08)
				(margins 0.9525 0.9525 0.9525 0.9525)
				(span 1 1)
				(fill
					(type none)
				)
				(effects
					(font
						(size 1.27 1.27)
					)
					(justify left top)
				)
			)
			(table_cell "Power rail"
				(exclude_from_sim no)
				(at 42.545 169.545 0)
				(size 22.86 5.08)
				(margins 0.9525 0.9525 0.9525 0.9525)
				(span 1 1)
				(fill
					(type none)
				)
				(effects
					(font
						(size 1.27 1.27)
					)
					(justify left top)
				)
			)
			(table_cell "EN_signal"
				(exclude_from_sim no)
				(at 65.405 169.545 0)
				(size 22.86 5.08)
				(margins 0.9525 0.9525 0.9525 0.9525)
				(span 1 1)
				(fill
					(type none)
				)
				(effects
					(font
						(size 1.27 1.27)
					)
					(justify left top)
				)
			)
			(table_cell "Delay"
				(exclude_from_sim no)
				(at 88.265 169.545 0)
				(size 22.86 5.08)
				(margins 0.9525 0.9525 0.9525 0.9525)
				(span 1 1)
				(fill
					(type none)
				)
				(effects
					(font
						(size 1.27 1.27)
					)
					(justify left top)
				)
			)
			(table_cell "1"
				(exclude_from_sim no)
				(at 19.685 174.625 0)
				(size 22.86 5.08)
				(margins 0.9525 0.9525 0.9525 0.9525)
				(span 1 1)
				(fill
					(type none)
				)
				(effects
					(font
						(size 1.27 1.27)
					)
					(justify left top)
				)
			)
			(table_cell "VCC(24V)"
				(exclude_from_sim no)
				(at 42.545 174.625 0)
				(size 22.86 5.08)
				(margins 0.9525 0.9525 0.9525 0.9525)
				(span 1 1)
				(fill
					(type none)
				)
				(effects
					(font
						(size 1.27 1.27)
					)
					(justify left top)
				)
			)
			(table_cell "-"
				(exclude_from_sim no)
				(at 65.405 174.625 0)
				(size 22.86 5.08)
				(margins 0.9525 0.9525 0.9525 0.9525)
				(span 1 1)
				(fill
					(type none)
				)
				(effects
					(font
						(size 1.27 1.27)
					)
					(justify left top)
				)
			)
			(table_cell "0"
				(exclude_from_sim no)
				(at 88.265 174.625 0)
				(size 22.86 5.08)
				(margins 0.9525 0.9525 0.9525 0.9525)
				(span 1 1)
				(fill
					(type none)
				)
				(effects
					(font
						(size 1.27 1.27)
					)
					(justify left top)
				)
			)
			(table_cell "2"
				(exclude_from_sim no)
				(at 19.685 179.705 0)
				(size 22.86 5.08)
				(margins 0.9525 0.9525 0.9525 0.9525)
				(span 1 1)
				(fill
					(type none)
				)
				(effects
					(font
						(size 1.27 1.27)
					)
					(justify left top)
				)
			)
			(table_cell "+5V_AON"
				(exclude_from_sim no)
				(at 42.545 179.705 0)
				(size 22.86 5.08)
				(margins 0.9525 0.9525 0.9525 0.9525)
				(span 1 1)
				(fill
					(type none)
				)
				(effects
					(font
						(size 1.27 1.27)
					)
					(justify left top)
				)
			)
			(table_cell "VCC pull-up"
				(exclude_from_sim no)
				(at 65.405 179.705 0)
				(size 22.86 5.08)
				(margins 0.9525 0.9525 0.9525 0.9525)
				(span 1 1)
				(fill
					(type none)
				)
				(effects
					(font
						(size 1.27 1.27)
					)
					(justify left top)
				)
			)
			(table_cell "0"
				(exclude_from_sim no)
				(at 88.265 179.705 0)
				(size 22.86 5.08)
				(margins 0.9525 0.9525 0.9525 0.9525)
				(span 1 1)
				(fill
					(type none)
				)
				(effects
					(font
						(size 1.27 1.27)
					)
					(justify left top)
				)
			)
			(table_cell "3"
				(exclude_from_sim no)
				(at 19.685 184.785 0)
				(size 22.86 5.08)
				(margins 0.9525 0.9525 0.9525 0.9525)
				(span 1 1)
				(fill
					(type none)
				)
				(effects
					(font
						(size 1.27 1.27)
					)
					(justify left top)
				)
			)
			(table_cell "+3V3_AON"
				(exclude_from_sim no)
				(at 42.545 184.785 0)
				(size 22.86 5.08)
				(margins 0.9525 0.9525 0.9525 0.9525)
				(span 1 1)
				(fill
					(type none)
				)
				(effects
					(font
						(size 1.27 1.27)
					)
					(justify left top)
				)
			)
			(table_cell "5V_AON"
				(exclude_from_sim no)
				(at 65.405 184.785 0)
				(size 22.86 5.08)
				(margins 0.9525 0.9525 0.9525 0.9525)
				(span 1 1)
				(fill
					(type none)
				)
				(effects
					(font
						(size 1.27 1.27)
					)
					(justify left top)
				)
			)
			(table_cell "0"
				(exclude_from_sim no)
				(at 88.265 184.785 0)
				(size 22.86 5.08)
				(margins 0.9525 0.9525 0.9525 0.9525)
				(span 1 1)
				(fill
					(type none)
				)
				(effects
					(font
						(size 1.27 1.27)
					)
					(justify left top)
				)
			)
			(table_cell "4"
				(exclude_from_sim no)
				(at 19.685 189.865 0)
				(size 22.86 5.08)
				(margins 0.9525 0.9525 0.9525 0.9525)
				(span 1 1)
				(fill
					(type none)
				)
				(effects
					(font
						(size 1.27 1.27)
					)
					(justify left top)
				)
			)
			(table_cell "+5V_SOM"
				(exclude_from_sim no)
				(at 42.545 189.865 0)
				(size 22.86 5.08)
				(margins 0.9525 0.9525 0.9525 0.9525)
				(span 1 1)
				(fill
					(type none)
				)
				(effects
					(font
						(size 1.27 1.27)
					)
					(justify left top)
				)
			)
			(table_cell "VIN_PWR_ON"
				(exclude_from_sim no)
				(at 65.405 189.865 0)
				(size 22.86 5.08)
				(margins 0.9525 0.9525 0.9525 0.9525)
				(span 1 1)
				(fill
					(type none)
				)
				(effects
					(font
						(size 1.27 1.27)
					)
					(justify left top)
				)
			)
			(table_cell ">=20ms"
				(exclude_from_sim no)
				(at 88.265 189.865 0)
				(size 22.86 5.08)
				(margins 0.9525 0.9525 0.9525 0.9525)
				(span 1 1)
				(fill
					(type none)
				)
				(effects
					(font
						(size 1.27 1.27)
					)
					(justify left top)
				)
			)
			(table_cell ""
				(exclude_from_sim no)
				(at 19.685 194.945 0)
				(size 22.86 5.08)
				(margins 0.9525 0.9525 0.9525 0.9525)
				(span 1 1)
				(fill
					(type none)
				)
				(effects
					(font
						(size 1.27 1.27)
					)
					(justify left top)
				)
			)
			(table_cell "SYS_VIN_HV"
				(exclude_from_sim no)
				(at 42.545 194.945 0)
				(size 22.86 5.08)
				(margins 0.9525 0.9525 0.9525 0.9525)
				(span 1 1)
				(fill
					(type none)
				)
				(effects
					(font
						(size 1.27 1.27)
					)
					(justify left top)
				)
			)
			(table_cell "VIN_PWR_ON"
				(exclude_from_sim no)
				(at 65.405 194.945 0)
				(size 22.86 5.08)
				(margins 0.9525 0.9525 0.9525 0.9525)
				(span 1 1)
				(fill
					(type none)
				)
				(effects
					(font
						(size 1.27 1.27)
					)
					(justify left top)
				)
			)
			(table_cell ">=20ms"
				(exclude_from_sim no)
				(at 88.265 194.945 0)
				(size 22.86 5.08)
				(margins 0.9525 0.9525 0.9525 0.9525)
				(span 1 1)
				(fill
					(type none)
				)
				(effects
					(font
						(size 1.27 1.27)
					)
					(justify left top)
				)
			)
			(table_cell "5"
				(exclude_from_sim no)
				(at 19.685 200.025 0)
				(size 22.86 5.08)
				(margins 0.9525 0.9525 0.9525 0.9525)
				(span 1 1)
				(fill
					(type none)
				)
				(effects
					(font
						(size 1.27 1.27)
					)
					(justify left top)
				)
			)
			(table_cell "MODULE_POWER_ON"
				(exclude_from_sim no)
				(at 42.545 200.025 0)
				(size 22.86 5.08)
				(margins 0.9525 0.9525 0.9525 0.9525)
				(span 1 1)
				(fill
					(type none)
				)
				(effects
					(font
						(size 1.27 1.27)
					)
					(justify left top)
				)
			)
			(table_cell "+5V_SOM & PG(SYS_VIN_HV)"
				(exclude_from_sim no)
				(at 65.405 200.025 0)
				(size 22.86 5.08)
				(margins 0.9525 0.9525 0.9525 0.9525)
				(span 1 1)
				(fill
					(type none)
				)
				(effects
					(font
						(size 1.27 1.27)
					)
					(justify left top)
				)
			)
			(table_cell ">=50ms"
				(exclude_from_sim no)
				(at 88.265 200.025 0)
				(size 22.86 5.08)
				(margins 0.9525 0.9525 0.9525 0.9525)
				(span 1 1)
				(fill
					(type none)
				)
				(effects
					(font
						(size 1.27 1.27)
					)
					(justify left top)
				)
			)
			(table_cell "6"
				(exclude_from_sim no)
				(at 19.685 205.105 0)
				(size 22.86 5.08)
				(margins 0.9525 0.9525 0.9525 0.9525)
				(span 1 1)
				(fill
					(type none)
				)
				(effects
					(font
						(size 1.27 1.27)
					)
					(justify left top)
				)
			)
			(table_cell "+3V3"
				(exclude_from_sim no)
				(at 42.545 205.105 0)
				(size 22.86 5.08)
				(margins 0.9525 0.9525 0.9525 0.9525)
				(span 1 1)
				(fill
					(type none)
				)
				(effects
					(font
						(size 1.27 1.27)
					)
					(justify left top)
				)
			)
			(table_cell "CARIER_POWER_ON"
				(exclude_from_sim no)
				(at 65.405 205.105 0)
				(size 22.86 5.08)
				(margins 0.9525 0.9525 0.9525 0.9525)
				(span 1 1)
				(fill
					(type none)
				)
				(effects
					(font
						(size 1.27 1.27)
					)
					(justify left top)
				)
			)
			(table_cell ""
				(exclude_from_sim no)
				(at 88.265 205.105 0)
				(size 22.86 5.08)
				(margins 0.9525 0.9525 0.9525 0.9525)
				(span 1 1)
				(fill
					(type none)
				)
				(effects
					(font
						(size 1.27 1.27)
					)
					(justify left top)
				)
			)
			(table_cell ""
				(exclude_from_sim no)
				(at 19.685 210.185 0)
				(size 22.86 5.08)
				(margins 0.9525 0.9525 0.9525 0.9525)
				(span 1 1)
				(fill
					(type none)
				)
				(effects
					(font
						(size 1.27 1.27)
					)
					(justify left top)
				)
			)
			(table_cell "+1V8"
				(exclude_from_sim no)
				(at 42.545 210.185 0)
				(size 22.86 5.08)
				(margins 0.9525 0.9525 0.9525 0.9525)
				(span 1 1)
				(fill
					(type none)
				)
				(effects
					(font
						(size 1.27 1.27)
					)
					(justify left top)
				)
			)
			(table_cell "CARIER_POWER_ON"
				(exclude_from_sim no)
				(at 65.405 210.185 0)
				(size 22.86 5.08)
				(margins 0.9525 0.9525 0.9525 0.9525)
				(span 1 1)
				(fill
					(type none)
				)
				(effects
					(font
						(size 1.27 1.27)
					)
					(justify left top)
				)
			)
			(table_cell ""
				(exclude_from_sim no)
				(at 88.265 210.185 0)
				(size 22.86 5.08)
				(margins 0.9525 0.9525 0.9525 0.9525)
				(span 1 1)
				(fill
					(type none)
				)
				(effects
					(font
						(size 1.27 1.27)
					)
					(justify left top)
				)
			)
			(table_cell ""
				(exclude_from_sim no)
				(at 19.685 215.265 0)
				(size 22.86 5.08)
				(margins 0.9525 0.9525 0.9525 0.9525)
				(span 1 1)
				(fill
					(type none)
				)
				(effects
					(font
						(size 1.27 1.27)
					)
					(justify left top)
				)
			)
			(table_cell "+12V"
				(exclude_from_sim no)
				(at 42.545 215.265 0)
				(size 22.86 5.08)
				(margins 0.9525 0.9525 0.9525 0.9525)
				(span 1 1)
				(fill
					(type none)
				)
				(effects
					(font
						(size 1.27 1.27)
					)
					(justify left top)
				)
			)
			(table_cell "CARIER_POWER_ON"
				(exclude_from_sim no)
				(at 65.405 215.265 0)
				(size 22.86 5.08)
				(margins 0.9525 0.9525 0.9525 0.9525)
				(span 1 1)
				(fill
					(type none)
				)
				(effects
					(font
						(size 1.27 1.27)
					)
					(justify left top)
				)
			)
			(table_cell ""
				(exclude_from_sim no)
				(at 88.265 215.265 0)
				(size 22.86 5.08)
				(margins 0.9525 0.9525 0.9525 0.9525)
				(span 1 1)
				(fill
					(type none)
				)
				(effects
					(font
						(size 1.27 1.27)
					)
					(justify left top)
				)
			)
			(table_cell ""
				(exclude_from_sim no)
				(at 19.685 220.345 0)
				(size 22.86 5.08)
				(margins 0.9525 0.9525 0.9525 0.9525)
				(span 1 1)
				(fill
					(type none)
				)
				(effects
					(font
						(size 1.27 1.27)
					)
					(justify left top)
				)
			)
			(table_cell "+5V"
				(exclude_from_sim no)
				(at 42.545 220.345 0)
				(size 22.86 5.08)
				(margins 0.9525 0.9525 0.9525 0.9525)
				(span 1 1)
				(fill
					(type none)
				)
				(effects
					(font
						(size 1.27 1.27)
					)
					(justify left top)
				)
			)
			(table_cell "CARIER_POWER_ON"
				(exclude_from_sim no)
				(at 65.405 220.345 0)
				(size 22.86 5.08)
				(margins 0.9525 0.9525 0.9525 0.9525)
				(span 1 1)
				(fill
					(type none)
				)
				(effects
					(font
						(size 1.27 1.27)
					)
					(justify left top)
				)
			)
			(table_cell ""
				(exclude_from_sim no)
				(at 88.265 220.345 0)
				(size 22.86 5.08)
				(margins 0.9525 0.9525 0.9525 0.9525)
				(span 1 1)
				(fill
					(type none)
				)
				(effects
					(font
						(size 1.27 1.27)
					)
					(justify left top)
				)
			)
		)
	)
	(label "VCC_IN_EN"
		(at 238.76 62.23 0)
		(effects
			(font
				(size 1.27 1.27)
			)
			(justify left bottom)
		)
	)
	(label "3V3_LDO"
		(at 114.3 81.28 180)
		(effects
			(font
				(size 1.27 1.27)
			)
			(justify right bottom)
		)
	)
	(hierarchical_label "USBPD2_HV"
		(shape bidirectional)
		(at 387.35 93.98 0)
		(effects
			(font
				(size 1.27 1.27)
			)
			(justify left)
		)
	)
	(hierarchical_label "USBPD2_HV"
		(shape bidirectional)
		(at 273.05 121.92 180)
		(effects
			(font
				(size 1.27 1.27)
			)
			(justify right)
		)
	)
	(hierarchical_label "USBPD1_HV"
		(shape bidirectional)
		(at 387.35 57.15 0)
		(effects
			(font
				(size 1.27 1.27)
			)
			(justify left)
		)
	)
	(hierarchical_label "USBPD1_HV"
		(shape bidirectional)
		(at 273.05 85.09 180)
		(effects
			(font
				(size 1.27 1.27)
			)
			(justify right)
		)
	)
	(symbol
		(lib_id "antmicropower:GND")
		(at 383.54 80.01 0)
		(unit 1)
		(exclude_from_sim no)
		(in_bom yes)
		(on_board yes)
		(dnp no)
		(property "Reference" "#PWR0613"
			(at 383.54 86.36 0)
			(effects
				(font
					(size 1.27 1.27)
				)
				(justify left bottom)
				(hide yes)
			)
		)
		(property "Value" "GND"
			(at 383.54 83.82 0)
			(effects
				(font
					(size 1.27 1.27)
					(thickness 0.15)
				)
			)
		)
		(property "Footprint" ""
			(at 392.43 87.63 0)
			(effects
				(font
					(size 1.27 1.27)
					(thickness 0.15)
				)
				(justify left bottom)
				(hide yes)
			)
		)
		(property "Datasheet" ""
			(at 392.43 92.71 0)
			(effects
				(font
					(size 1.27 1.27)
					(thickness 0.15)
				)
				(justify left bottom)
				(hide yes)
			)
		)
		(property "Description" ""
			(at 383.54 80.01 0)
			(effects
				(font
					(size 1.27 1.27)
				)
				(hide yes)
			)
		)
		(property "Author" "Antmicro"
			(at 392.43 87.63 0)
			(effects
				(font
					(size 1.27 1.27)
					(thickness 0.15)
				)
				(justify left bottom)
				(hide yes)
			)
		)
		(property "License" "Apache-2.0"
			(at 392.43 90.17 0)
			(effects
				(font
					(size 1.27 1.27)
					(thickness 0.15)
				)
				(justify left bottom)
				(hide yes)
			)
		)
		(pin "1"
		)
		(instances
			(project "jetson-agx-thor-baseboard"
				(path ""
					(reference "#PWR0613")
					(unit 1)
				)
			)
		)
	)
	(symbol
		(lib_id "antmicroMechanicalParts:Lightpipe_Bivar_SLP3-150-150-F")
		(at 250.19 227.33 0)
		(unit 1)
		(exclude_from_sim no)
		(in_bom yes)
		(on_board yes)
		(dnp no)
		(fields_autoplaced yes)
		(property "Reference" "H15"
			(at 256.54 225.7617 0)
			(effects
				(font
					(size 1.27 1.27)
					(thickness 0.15)
				)
				(justify left)
			)
		)
		(property "Value" "Lightpipe_Bivar_SLP3-150-150-F"
			(at 261.95 234.645 0)
			(effects
				(font
					(size 1.27 1.27)
					(thickness 0.15)
				)
				(justify left bottom)
				(hide yes)
			)
		)
		(property "Footprint" "antmicro-footprints:Mech_Lightpipe_Bivar_SLP3-150-150-F"
			(at 261.95 237.185 0)
			(effects
				(font
					(size 1.27 1.27)
					(thickness 0.15)
				)
				(justify left bottom)
				(hide yes)
			)
		)
		(property "Datasheet" "https://eu.mouser.com/datasheet/2/50/Bivar_SLP3_150_XXX_X_N-3318840.pdf"
			(at 261.95 239.725 0)
			(effects
				(font
					(size 1.27 1.27)
					(thickness 0.15)
				)
				(justify left bottom)
				(hide yes)
			)
		)
		(property "Description" "LED Light Pipe, Rigid Board, Horizontal"
			(at 261.95 249.885 0)
			(effects
				(font
					(size 1.27 1.27)
				)
				(justify left bottom)
				(hide yes)
			)
		)
		(property "Manufacturer" "BIVAR"
			(at 261.95 242.265 0)
			(effects
				(font
					(size 1.27 1.27)
					(thickness 0.15)
				)
				(justify left bottom)
				(hide yes)
			)
		)
		(property "MPN" "SLP3-150-150-F"
			(at 256.54 228.3017 0)
			(effects
				(font
					(size 1.27 1.27)
					(thickness 0.15)
				)
				(justify left)
			)
		)
		(property "Author" "Antmicro"
			(at 261.95 244.805 0)
			(effects
				(font
					(size 1.27 1.27)
					(thickness 0.15)
				)
				(justify left bottom)
				(hide yes)
			)
		)
		(property "License" "Apache-2.0"
			(at 261.95 247.345 0)
			(effects
				(font
					(size 1.27 1.27)
					(thickness 0.15)
				)
				(justify left bottom)
				(hide yes)
			)
		)
		(instances
			(project "jetson-agx-thor-baseboard"
				(path ""
					(reference "H15")
					(unit 1)
				)
			)
		)
	)
	(symbol
		(lib_id "antmicropower:+1V8")
		(at 336.55 207.01 0)
		(unit 1)
		(exclude_from_sim no)
		(in_bom yes)
		(on_board yes)
		(dnp no)
		(property "Reference" "#PWR0176"
			(at 351.79 209.55 0)
			(effects
				(font
					(size 1.27 1.27)
					(thickness 0.15)
				)
				(justify left bottom)
				(hide yes)
			)
		)
		(property "Value" "+1V8"
			(at 336.55 203.2 0)
			(effects
				(font
					(size 1.27 1.27)
					(thickness 0.15)
				)
			)
		)
		(property "Footprint" ""
			(at 351.79 214.63 0)
			(effects
				(font
					(size 1.27 1.27)
					(thickness 0.15)
				)
				(justify left bottom)
				(hide yes)
			)
		)
		(property "Datasheet" ""
			(at 351.79 217.17 0)
			(effects
				(font
					(size 1.27 1.27)
					(thickness 0.15)
				)
				(justify left bottom)
				(hide yes)
			)
		)
		(property "Description" ""
			(at 336.55 207.01 0)
			(effects
				(font
					(size 1.27 1.27)
				)
				(hide yes)
			)
		)
		(property "Author" "Antmicro"
			(at 351.79 212.09 0)
			(effects
				(font
					(size 1.27 1.27)
					(thickness 0.15)
				)
				(justify left bottom)
				(hide yes)
			)
		)
		(property "License" "Apache-2.0"
			(at 351.79 214.63 0)
			(effects
				(font
					(size 1.27 1.27)
					(thickness 0.15)
				)
				(justify left bottom)
				(hide yes)
			)
		)
		(pin "1"
		)
		(instances
			(project "jetson-agx-thor-baseboard"
				(path ""
					(reference "#PWR0176")
					(unit 1)
				)
			)
		)
	)
	(symbol
		(lib_id "antmicroTransistorsFETsMOSFETsSingle:SISS05DN-T1-GE3")
		(at 302.26 57.15 270)
		(mirror x)
		(unit 1)
		(exclude_from_sim no)
		(in_bom yes)
		(on_board yes)
		(dnp no)
		(property "Reference" "Q42"
			(at 305.054 45.974 90)
			(effects
				(font
					(size 1.27 1.27)
					(thickness 0.15)
				)
			)
		)
		(property "Value" "SISS05DN-T1-GE3"
			(at 292.1 41.91 0)
			(effects
				(font
					(size 1.27 1.27)
					(thickness 0.15)
				)
				(justify left bottom)
				(hide yes)
			)
		)
		(property "Footprint" "antmicro-footprints:Vishay_PowerPAK_1212-8_Single"
			(at 289.56 41.91 0)
			(effects
				(font
					(size 1.27 1.27)
					(thickness 0.15)
				)
				(justify left bottom)
				(hide yes)
			)
		)
		(property "Datasheet" "https://www.vishay.com/docs/77029/siss05dn.pdf"
			(at 287.02 41.91 0)
			(effects
				(font
					(size 1.27 1.27)
					(thickness 0.15)
				)
				(justify left bottom)
				(hide yes)
			)
		)
		(property "Description" "Power MOSFET, P Channel, 30 V, 108 A, 0.0035 ohm, PowerPAK 1212, Surface Mount"
			(at 284.48 41.91 0)
			(effects
				(font
					(size 1.27 1.27)
					(thickness 0.15)
				)
				(justify left bottom)
				(hide yes)
			)
		)
		(property "MPN" "SISS05DN-T1-GE3"
			(at 304.8 47.752 90)
			(effects
				(font
					(size 1.27 1.27)
					(thickness 0.15)
				)
			)
		)
		(property "Manufacturer" "Vishay"
			(at 281.94 41.91 0)
			(effects
				(font
					(size 1.27 1.27)
					(thickness 0.15)
				)
				(justify left bottom)
				(hide yes)
			)
		)
		(property "Author" "Antmicro"
			(at 279.4 41.91 0)
			(effects
				(font
					(size 1.27 1.27)
					(thickness 0.15)
				)
				(justify left bottom)
				(hide yes)
			)
		)
		(property "License" "Apache-2.0"
			(at 276.86 41.91 0)
			(effects
				(font
					(size 1.27 1.27)
					(thickness 0.15)
				)
				(justify left bottom)
				(hide yes)
			)
		)
		(pin "1"
		)
		(pin "4"
		)
		(pin "3"
		)
		(pin "5"
		)
		(pin "2"
		)
		(instances
			(project "jetson-agx-thor-baseboard"
				(path ""
					(reference "Q42")
					(unit 1)
				)
			)
		)
	)
	(symbol
		(lib_id "antmicroTransistorsFETsMOSFETsSingle:DMG1012T-7")
		(at 339.09 210.82 0)
		(unit 1)
		(exclude_from_sim no)
		(in_bom yes)
		(on_board yes)
		(dnp no)
		(fields_autoplaced yes)
		(property "Reference" "Q16"
			(at 349.25 207.01 0)
			(effects
				(font
					(size 1.27 1.27)
					(thickness 0.15)
				)
				(justify left)
			)
		)
		(property "Value" "DMG1012T-7"
			(at 361.95 219.71 0)
			(effects
				(font
					(size 1.27 1.27)
					(thickness 0.15)
				)
				(justify left bottom)
				(hide yes)
			)
		)
		(property "Footprint" "antmicro-footprints:SOT-523"
			(at 361.95 222.25 0)
			(effects
				(font
					(size 1.27 1.27)
					(thickness 0.15)
				)
				(justify left bottom)
				(hide yes)
			)
		)
		(property "Datasheet" "https://www.diodes.com/assets/Datasheets/ds31783.pdf"
			(at 361.95 224.79 0)
			(effects
				(font
					(size 1.27 1.27)
					(thickness 0.15)
				)
				(justify left bottom)
				(hide yes)
			)
		)
		(property "Description" "Power MOSFET, N Channel, 20 V, 630 mA, 0.3 ohm, SOT-523, Surface Mount"
			(at 361.95 237.49 0)
			(effects
				(font
					(size 1.27 1.27)
				)
				(justify left bottom)
				(hide yes)
			)
		)
		(property "MPN" "DMG1012T-7"
			(at 349.25 209.55 0)
			(effects
				(font
					(size 1.27 1.27)
					(thickness 0.15)
				)
				(justify left)
			)
		)
		(property "Manufacturer" "Diodes Incorporated"
			(at 361.95 229.87 0)
			(effects
				(font
					(size 1.27 1.27)
					(thickness 0.15)
				)
				(justify left bottom)
				(hide yes)
			)
		)
		(property "Author" "Antmicro"
			(at 361.95 232.41 0)
			(effects
				(font
					(size 1.27 1.27)
					(thickness 0.15)
				)
				(justify left bottom)
				(hide yes)
			)
		)
		(property "License" "Apache-2.0"
			(at 361.95 234.95 0)
			(effects
				(font
					(size 1.27 1.27)
					(thickness 0.15)
				)
				(justify left bottom)
				(hide yes)
			)
		)
		(pin "3"
		)
		(pin "2"
		)
		(pin "1"
		)
		(instances
			(project "jetson-agx-thor-baseboard"
				(path ""
					(reference "Q16")
					(unit 1)
				)
			)
		)
	)
	(symbol
		(lib_id "antmicroTestPoints:TP_0.75mm_SMD")
		(at 317.5 203.2 0)
		(mirror x)
		(unit 1)
		(exclude_from_sim no)
		(in_bom no)
		(on_board yes)
		(dnp no)
		(property "Reference" "TP63"
			(at 321.818 203.2 0)
			(effects
				(font
					(size 1.27 1.27)
				)
				(justify left)
			)
		)
		(property "Value" "TP_0.75mm_SMD"
			(at 327.66 199.39 0)
			(effects
				(font
					(size 1.27 1.27)
					(thickness 0.15)
				)
				(justify left bottom)
				(hide yes)
			)
		)
		(property "Footprint" "antmicro-footprints:TP_SMD_0.75mm"
			(at 327.66 196.85 0)
			(effects
				(font
					(size 1.27 1.27)
					(thickness 0.15)
				)
				(justify left bottom)
				(hide yes)
			)
		)
		(property "Datasheet" ""
			(at 335.28 190.5 0)
			(effects
				(font
					(size 1.27 1.27)
					(thickness 0.15)
				)
				(justify left bottom)
				(hide yes)
			)
		)
		(property "Description" "SMT test point"
			(at 317.5 203.2 0)
			(effects
				(font
					(size 1.27 1.27)
				)
				(hide yes)
			)
		)
		(property "MPN" ""
			(at 328.295 191.77 0)
			(effects
				(font
					(size 1.27 1.27)
					(thickness 0.15)
				)
				(justify left bottom)
				(hide yes)
			)
		)
		(property "Manufacturer" ""
			(at 328.295 196.85 0)
			(effects
				(font
					(size 1.27 1.27)
					(thickness 0.15)
				)
				(justify left bottom)
				(hide yes)
			)
		)
		(property "Author" "Antmicro"
			(at 327.66 194.31 0)
			(effects
				(font
					(size 1.27 1.27)
					(thickness 0.15)
				)
				(justify left bottom)
				(hide yes)
			)
		)
		(property "License" "Apache-2.0"
			(at 327.66 191.77 0)
			(effects
				(font
					(size 1.27 1.27)
					(thickness 0.15)
				)
				(justify left bottom)
				(hide yes)
			)
		)
		(pin "1"
		)
		(instances
			(project "jetson-agx-thor-baseboard"
				(path ""
					(reference "TP63")
					(unit 1)
				)
			)
		)
	)
	(symbol
		(lib_id "antmicroTestPoints:TP_0.75mm_SMD")
		(at 237.49 62.23 180)
		(unit 1)
		(exclude_from_sim no)
		(in_bom no)
		(on_board yes)
		(dnp no)
		(property "Reference" "TP116"
			(at 230.378 62.23 0)
			(effects
				(font
					(size 1.27 1.27)
					(thickness 0.15)
				)
			)
		)
		(property "Value" "TP_0.75mm_SMD"
			(at 227.33 58.42 0)
			(effects
				(font
					(size 1.27 1.27)
					(thickness 0.15)
				)
				(justify left bottom)
				(hide yes)
			)
		)
		(property "Footprint" "antmicro-footprints:TP_SMD_0.75mm"
			(at 227.33 55.88 0)
			(effects
				(font
					(size 1.27 1.27)
					(thickness 0.15)
				)
				(justify left bottom)
				(hide yes)
			)
		)
		(property "Datasheet" ""
			(at 219.71 49.53 0)
			(effects
				(font
					(size 1.27 1.27)
					(thickness 0.15)
				)
				(justify left bottom)
				(hide yes)
			)
		)
		(property "Description" "SMT test point"
			(at 226.695 48.26 0)
			(effects
				(font
					(size 1.27 1.27)
				)
				(justify left bottom)
				(hide yes)
			)
		)
		(property "MPN" ""
			(at 226.695 50.8 0)
			(effects
				(font
					(size 1.27 1.27)
					(thickness 0.15)
				)
				(justify left bottom)
				(hide yes)
			)
		)
		(property "Manufacturer" ""
			(at 226.695 55.88 0)
			(effects
				(font
					(size 1.27 1.27)
					(thickness 0.15)
				)
				(justify left bottom)
				(hide yes)
			)
		)
		(property "Author" "Antmicro"
			(at 227.33 53.34 0)
			(effects
				(font
					(size 1.27 1.27)
					(thickness 0.15)
				)
				(justify left bottom)
				(hide yes)
			)
		)
		(property "License" "Apache-2.0"
			(at 227.33 50.8 0)
			(effects
				(font
					(size 1.27 1.27)
					(thickness 0.15)
				)
				(justify left bottom)
				(hide yes)
			)
		)
		(pin "1"
		)
		(instances
			(project ""
				(path ""
					(reference "TP116")
					(unit 1)
				)
			)
		)
	)
	(symbol
		(lib_id "antmicroCapacitors0402:C_100n_0402")
		(at 276.86 105.41 90)
		(unit 1)
		(exclude_from_sim no)
		(in_bom no)
		(on_board yes)
		(dnp yes)
		(fields_autoplaced yes)
		(property "Reference" "C38"
			(at 274.32 101.5936 90)
			(effects
				(font
					(size 1.27 1.27)
					(thickness 0.15)
				)
				(justify left)
			)
		)
		(property "Value" "C_100n_0402"
			(at 299.72 90.17 0)
			(effects
				(font
					(size 1.27 1.27)
					(thickness 0.15)
				)
				(justify left bottom)
				(hide yes)
			)
		)
		(property "Footprint" "antmicro-footprints:C_0402_1005Metric"
			(at 302.26 90.17 0)
			(effects
				(font
					(size 1.27 1.27)
					(thickness 0.15)
				)
				(justify left bottom)
				(hide yes)
			)
		)
		(property "Datasheet" "https://www.murata.com/products/productdetail?partno=GRM155R61H104KE14%23"
			(at 304.8 90.17 0)
			(effects
				(font
					(size 1.27 1.27)
					(thickness 0.15)
				)
				(justify left bottom)
				(hide yes)
			)
		)
		(property "Description" "SMD Multilayer Ceramic Capacitor, 0.1 µF, 50 V, 0402 [1005 Metric], ± 10%, X5R, GRM Series"
			(at 276.86 105.41 0)
			(effects
				(font
					(size 1.27 1.27)
				)
				(hide yes)
			)
		)
		(property "MPN" "GRM155R61H104KE14D"
			(at 307.34 90.17 0)
			(effects
				(font
					(size 1.27 1.27)
					(thickness 0.15)
				)
				(justify left bottom)
				(hide yes)
			)
		)
		(property "Val" "100n"
			(at 274.32 104.1336 90)
			(effects
				(font
					(size 1.27 1.27)
					(thickness 0.15)
				)
				(justify left)
			)
		)
		(property "Voltage" "50V"
			(at 287.02 90.17 0)
			(effects
				(font
					(size 1.27 1.27)
					(thickness 0.15)
				)
				(justify left bottom)
				(hide yes)
			)
		)
		(property "Dielectric" "X5R"
			(at 289.56 90.17 0)
			(effects
				(font
					(size 1.27 1.27)
					(thickness 0.15)
				)
				(justify left bottom)
				(hide yes)
			)
		)
		(property "Manufacturer" "Murata"
			(at 292.1 90.17 0)
			(effects
				(font
					(size 1.27 1.27)
					(thickness 0.15)
				)
				(justify left bottom)
				(hide yes)
			)
		)
		(property "License" "Apache-2.0"
			(at 294.64 90.17 0)
			(effects
				(font
					(size 1.27 1.27)
					(thickness 0.15)
				)
				(justify left bottom)
				(hide yes)
			)
		)
		(property "Author" "Antmicro"
			(at 297.18 90.17 0)
			(effects
				(font
					(size 1.27 1.27)
					(thickness 0.15)
				)
				(justify left bottom)
				(hide yes)
			)
		)
		(pin "1"
		)
		(pin "2"
		)
		(instances
			(project "jetson-agx-thor-baseboard"
				(path ""
					(reference "C38")
					(unit 1)
				)
			)
		)
	)
	(symbol
		(lib_id "antmicroResistors0402:R_2k2_0402")
		(at 228.6 209.55 90)
		(unit 1)
		(exclude_from_sim no)
		(in_bom yes)
		(on_board yes)
		(dnp no)
		(fields_autoplaced yes)
		(property "Reference" "R17"
			(at 231.14 205.74 90)
			(effects
				(font
					(size 1.27 1.27)
					(thickness 0.15)
				)
				(justify right)
			)
		)
		(property "Value" "R_2k2_0402"
			(at 241.3 189.23 0)
			(effects
				(font
					(size 1.27 1.27)
					(thickness 0.15)
				)
				(justify left bottom)
				(hide yes)
			)
		)
		(property "Footprint" "antmicro-footprints:R_0402_1005Metric"
			(at 243.84 189.23 0)
			(effects
				(font
					(size 1.27 1.27)
					(thickness 0.15)
				)
				(justify left bottom)
				(hide yes)
			)
		)
		(property "Datasheet" "https://www.bourns.com/docs/product-datasheets/cr.pdf"
			(at 246.38 189.23 0)
			(effects
				(font
					(size 1.27 1.27)
					(thickness 0.15)
				)
				(justify left bottom)
				(hide yes)
			)
		)
		(property "Description" "SMD Chip Resistor, 2.2 kohm, ± 1%, 62.5 mW, 0402 [1005 Metric], Thick Film, General Purpose"
			(at 228.6 209.55 0)
			(effects
				(font
					(size 1.27 1.27)
				)
				(hide yes)
			)
		)
		(property "MPN" "CR0402-FX-2201GLF"
			(at 248.92 189.23 0)
			(effects
				(font
					(size 1.27 1.27)
					(thickness 0.15)
				)
				(justify left bottom)
				(hide yes)
			)
		)
		(property "Manufacturer" "Bourns"
			(at 251.46 189.23 0)
			(effects
				(font
					(size 1.27 1.27)
					(thickness 0.15)
				)
				(justify left bottom)
				(hide yes)
			)
		)
		(property "License" "Apache-2.0"
			(at 254 189.23 0)
			(effects
				(font
					(size 1.27 1.27)
					(thickness 0.15)
				)
				(justify left bottom)
				(hide yes)
			)
		)
		(property "Author" "Antmicro"
			(at 256.54 189.23 0)
			(effects
				(font
					(size 1.27 1.27)
					(thickness 0.15)
				)
				(justify left bottom)
				(hide yes)
			)
		)
		(property "Val" "2k2"
			(at 231.14 208.28 90)
			(effects
				(font
					(size 1.27 1.27)
					(thickness 0.15)
				)
				(justify right)
			)
		)
		(property "Tolerance" "1%"
			(at 238.76 189.23 0)
			(effects
				(font
					(size 1.27 1.27)
				)
				(justify left bottom)
				(hide yes)
			)
		)
		(pin "2"
		)
		(pin "1"
		)
		(instances
			(project "jetson-agx-thor-baseboard"
				(path ""
					(reference "R17")
					(unit 1)
				)
			)
		)
	)
	(symbol
		(lib_id "antmicroTransistorsFETsMOSFETsSingle:SISS05DN-T1-GE3")
		(at 378.46 63.5 90)
		(unit 1)
		(exclude_from_sim no)
		(in_bom yes)
		(on_board yes)
		(dnp no)
		(fields_autoplaced yes)
		(property "Reference" "Q24"
			(at 375.92 50.8 90)
			(effects
				(font
					(size 1.27 1.27)
					(thickness 0.15)
				)
			)
		)
		(property "Value" "SISS05DN-T1-GE3"
			(at 388.62 48.26 0)
			(effects
				(font
					(size 1.27 1.27)
					(thickness 0.15)
				)
				(justify left bottom)
				(hide yes)
			)
		)
		(property "Footprint" "antmicro-footprints:Vishay_PowerPAK_1212-8_Single"
			(at 391.16 48.26 0)
			(effects
				(font
					(size 1.27 1.27)
					(thickness 0.15)
				)
				(justify left bottom)
				(hide yes)
			)
		)
		(property "Datasheet" "https://www.vishay.com/docs/77029/siss05dn.pdf"
			(at 393.7 48.26 0)
			(effects
				(font
					(size 1.27 1.27)
					(thickness 0.15)
				)
				(justify left bottom)
				(hide yes)
			)
		)
		(property "Description" "Power MOSFET, P Channel, 30 V, 108 A, 0.0035 ohm, PowerPAK 1212, Surface Mount"
			(at 396.24 48.26 0)
			(effects
				(font
					(size 1.27 1.27)
					(thickness 0.15)
				)
				(justify left bottom)
				(hide yes)
			)
		)
		(property "MPN" "SISS05DN-T1-GE3"
			(at 375.92 53.34 90)
			(effects
				(font
					(size 1.27 1.27)
					(thickness 0.15)
				)
			)
		)
		(property "Manufacturer" "Vishay"
			(at 398.78 48.26 0)
			(effects
				(font
					(size 1.27 1.27)
					(thickness 0.15)
				)
				(justify left bottom)
				(hide yes)
			)
		)
		(property "Author" "Antmicro"
			(at 401.32 48.26 0)
			(effects
				(font
					(size 1.27 1.27)
					(thickness 0.15)
				)
				(justify left bottom)
				(hide yes)
			)
		)
		(property "License" "Apache-2.0"
			(at 403.86 48.26 0)
			(effects
				(font
					(size 1.27 1.27)
					(thickness 0.15)
				)
				(justify left bottom)
				(hide yes)
			)
		)
		(pin "1"
		)
		(pin "4"
		)
		(pin "3"
		)
		(pin "5"
		)
		(pin "2"
		)
		(instances
			(project "jetson-agx-thor-baseboard"
				(path ""
					(reference "Q24")
					(unit 1)
				)
			)
		)
	)
	(symbol
		(lib_id "antmicroPMICORControllersIdealDiodes:LTC4412IS6")
		(at 284.48 135.89 0)
		(unit 1)
		(exclude_from_sim no)
		(in_bom no)
		(on_board yes)
		(dnp yes)
		(fields_autoplaced yes)
		(property "Reference" "U62"
			(at 293.37 128.27 0)
			(effects
				(font
					(size 1.27 1.27)
					(thickness 0.15)
				)
			)
		)
		(property "Value" "LTC4412IS6"
			(at 316.23 140.97 0)
			(effects
				(font
					(size 1.27 1.27)
					(thickness 0.15)
				)
				(justify left bottom)
				(hide yes)
			)
		)
		(property "Footprint" "antmicro-footprints:SOT-23-6"
			(at 316.23 143.51 0)
			(effects
				(font
					(size 1.27 1.27)
					(thickness 0.15)
				)
				(justify left bottom)
				(hide yes)
			)
		)
		(property "Datasheet" "https://www.analog.com/media/en/technical-documentation/data-sheets/4412fb.pdf"
			(at 316.23 146.05 0)
			(effects
				(font
					(size 1.27 1.27)
					(thickness 0.15)
				)
				(justify left bottom)
				(hide yes)
			)
		)
		(property "Description" "Ideal diode controller"
			(at 284.48 135.89 0)
			(effects
				(font
					(size 1.27 1.27)
				)
				(hide yes)
			)
		)
		(property "MPN" "LTC4412IS6#TRMPBF"
			(at 293.37 130.81 0)
			(effects
				(font
					(size 1.27 1.27)
					(thickness 0.15)
				)
			)
		)
		(property "Manufacturer" "Analog Devices"
			(at 316.23 151.13 0)
			(effects
				(font
					(size 1.27 1.27)
					(thickness 0.15)
				)
				(justify left bottom)
				(hide yes)
			)
		)
		(property "Author" "Antmicro"
			(at 316.23 153.67 0)
			(effects
				(font
					(size 1.27 1.27)
					(thickness 0.15)
				)
				(justify left bottom)
				(hide yes)
			)
		)
		(property "License" "Apache-2.0"
			(at 316.23 156.21 0)
			(effects
				(font
					(size 1.27 1.27)
					(thickness 0.15)
				)
				(justify left bottom)
				(hide yes)
			)
		)
		(pin "3"
		)
		(pin "5"
		)
		(pin "4"
		)
		(pin "2"
		)
		(pin "1"
		)
		(pin "6"
		)
		(instances
			(project "jetson-agx-thor-baseboard"
				(path ""
					(reference "U62")
					(unit 1)
				)
			)
		)
	)
	(symbol
		(lib_id "antmicroCapacitors0603:C_22u_16V_0603")
		(at 60.96 87.63 90)
		(unit 1)
		(exclude_from_sim no)
		(in_bom yes)
		(on_board yes)
		(dnp no)
		(property "Reference" "C62"
			(at 62.865 83.82 90)
			(effects
				(font
					(size 1.27 1.27)
				)
				(justify right)
			)
		)
		(property "Value" "C_22u_16V_0603"
			(at 71.12 67.31 0)
			(effects
				(font
					(size 1.27 1.27)
					(thickness 0.15)
				)
				(justify left bottom)
				(hide yes)
			)
		)
		(property "Footprint" "antmicro-footprints:C_0603_1608Metric_EIA"
			(at 73.66 67.31 0)
			(effects
				(font
					(size 1.27 1.27)
					(thickness 0.15)
				)
				(justify left bottom)
				(hide yes)
			)
		)
		(property "Datasheet" "https://product.samsungsem.com/mlcc/CL10A226MO7JZN.do"
			(at 76.2 67.31 0)
			(effects
				(font
					(size 1.27 1.27)
					(thickness 0.15)
				)
				(justify left bottom)
				(hide yes)
			)
		)
		(property "Description" "SMD Multilayer Ceramic Capacitor"
			(at 60.96 87.63 0)
			(effects
				(font
					(size 1.27 1.27)
				)
				(hide yes)
			)
		)
		(property "Manufacturer" "Samsung Electro-Mechanics"
			(at 81.28 67.31 0)
			(effects
				(font
					(size 1.27 1.27)
					(thickness 0.15)
				)
				(justify left bottom)
				(hide yes)
			)
		)
		(property "MPN" "CL10A226MO7JZNC"
			(at 78.74 67.31 0)
			(effects
				(font
					(size 1.27 1.27)
					(thickness 0.15)
				)
				(justify left bottom)
				(hide yes)
			)
		)
		(property "Val" "22u"
			(at 62.865 86.36 90)
			(effects
				(font
					(size 1.27 1.27)
					(thickness 0.15)
				)
				(justify right)
			)
		)
		(property "License" "Apache-2.0"
			(at 83.82 67.31 0)
			(effects
				(font
					(size 1.27 1.27)
					(thickness 0.15)
				)
				(justify left bottom)
				(hide yes)
			)
		)
		(property "Author" "Antmicro"
			(at 86.36 67.31 0)
			(effects
				(font
					(size 1.27 1.27)
					(thickness 0.15)
				)
				(justify left bottom)
				(hide yes)
			)
		)
		(property "Voltage" "16V"
			(at 88.9 67.31 0)
			(effects
				(font
					(size 1.27 1.27)
				)
				(justify left bottom)
				(hide yes)
			)
		)
		(property "Dielectric" ""
			(at 91.44 67.31 0)
			(effects
				(font
					(size 1.27 1.27)
				)
				(justify left bottom)
				(hide yes)
			)
		)
		(pin "1"
		)
		(pin "2"
		)
		(instances
			(project "jetson-agx-thor-baseboard"
				(path ""
					(reference "C62")
					(unit 1)
				)
			)
		)
	)
	(symbol
		(lib_id "antmicroLEDIndicationDiscrete:LED_G_0603_LTST-C190GKT")
		(at 259.08 215.9 90)
		(unit 1)
		(exclude_from_sim no)
		(in_bom yes)
		(on_board yes)
		(dnp no)
		(property "Reference" "D12"
			(at 260.35 212.09 90)
			(effects
				(font
					(size 1.27 1.27)
				)
				(justify right)
			)
		)
		(property "Value" "LED_G_0603_LTST-C190GKT"
			(at 266.7 193.04 0)
			(effects
				(font
					(size 1.27 1.27)
					(thickness 0.15)
				)
				(justify left bottom)
				(hide yes)
			)
		)
		(property "Footprint" "antmicro-footprints:LED_0603_1608Metric_G"
			(at 269.24 193.04 0)
			(effects
				(font
					(size 1.27 1.27)
					(thickness 0.15)
				)
				(justify left bottom)
				(hide yes)
			)
		)
		(property "Datasheet" "https://media.digikey.com/pdf/Data%20Sheets/Lite-On%20PDFs/LTST-C190GKT.pdf"
			(at 271.78 193.04 0)
			(effects
				(font
					(size 1.27 1.27)
					(thickness 0.15)
				)
				(justify left bottom)
				(hide yes)
			)
		)
		(property "Description" "LED, Green, SMD, 0603, 20 mA, 2.1 V, 569 nm"
			(at 259.08 215.9 0)
			(effects
				(font
					(size 1.27 1.27)
				)
				(hide yes)
			)
		)
		(property "MPN" "LTST-C190GKT"
			(at 274.32 193.04 0)
			(effects
				(font
					(size 1.27 1.27)
					(thickness 0.15)
				)
				(justify left bottom)
				(hide yes)
			)
		)
		(property "Manufacturer" "Lite-On"
			(at 276.86 193.04 0)
			(effects
				(font
					(size 1.27 1.27)
					(thickness 0.15)
				)
				(justify left bottom)
				(hide yes)
			)
		)
		(property "Author" "Antmicro"
			(at 279.4 193.04 0)
			(effects
				(font
					(size 1.27 1.27)
					(thickness 0.15)
				)
				(justify left bottom)
				(hide yes)
			)
		)
		(property "License" "Apache-2.0"
			(at 281.94 193.04 0)
			(effects
				(font
					(size 1.27 1.27)
					(thickness 0.15)
				)
				(justify left bottom)
				(hide yes)
			)
		)
		(property "Color" "Green"
			(at 260.35 214.63 90)
			(effects
				(font
					(size 1.27 1.27)
				)
				(justify right)
			)
		)
		(pin "1"
		)
		(pin "2"
		)
		(instances
			(project "jetson-agx-thor-baseboard"
				(path ""
					(reference "D12")
					(unit 1)
				)
			)
		)
	)
	(symbol
		(lib_id "antmicroPMICORControllersIdealDiodes:LTC4412IS6")
		(at 359.41 107.95 0)
		(unit 1)
		(exclude_from_sim no)
		(in_bom yes)
		(on_board yes)
		(dnp no)
		(fields_autoplaced yes)
		(property "Reference" "U64"
			(at 368.3 100.33 0)
			(effects
				(font
					(size 1.27 1.27)
					(thickness 0.15)
				)
			)
		)
		(property "Value" "LTC4412IS6"
			(at 391.16 113.03 0)
			(effects
				(font
					(size 1.27 1.27)
					(thickness 0.15)
				)
				(justify left bottom)
				(hide yes)
			)
		)
		(property "Footprint" "antmicro-footprints:SOT-23-6"
			(at 391.16 115.57 0)
			(effects
				(font
					(size 1.27 1.27)
					(thickness 0.15)
				)
				(justify left bottom)
				(hide yes)
			)
		)
		(property "Datasheet" "https://www.analog.com/media/en/technical-documentation/data-sheets/4412fb.pdf"
			(at 391.16 118.11 0)
			(effects
				(font
					(size 1.27 1.27)
					(thickness 0.15)
				)
				(justify left bottom)
				(hide yes)
			)
		)
		(property "Description" "Ideal diode controller"
			(at 359.41 107.95 0)
			(effects
				(font
					(size 1.27 1.27)
				)
				(hide yes)
			)
		)
		(property "MPN" "LTC4412IS6#TRMPBF"
			(at 368.3 102.87 0)
			(effects
				(font
					(size 1.27 1.27)
					(thickness 0.15)
				)
			)
		)
		(property "Manufacturer" "Analog Devices"
			(at 391.16 123.19 0)
			(effects
				(font
					(size 1.27 1.27)
					(thickness 0.15)
				)
				(justify left bottom)
				(hide yes)
			)
		)
		(property "Author" "Antmicro"
			(at 391.16 125.73 0)
			(effects
				(font
					(size 1.27 1.27)
					(thickness 0.15)
				)
				(justify left bottom)
				(hide yes)
			)
		)
		(property "License" "Apache-2.0"
			(at 391.16 128.27 0)
			(effects
				(font
					(size 1.27 1.27)
					(thickness 0.15)
				)
				(justify left bottom)
				(hide yes)
			)
		)
		(pin "3"
		)
		(pin "5"
		)
		(pin "4"
		)
		(pin "2"
		)
		(pin "1"
		)
		(pin "6"
		)
		(instances
			(project "jetson-agx-thor-baseboard"
				(path ""
					(reference "U64")
					(unit 1)
				)
			)
		)
	)
	(symbol
		(lib_id "antmicroTransistorsFETsMOSFETsSingle:SISS05DN-T1-GE3")
		(at 303.53 128.27 90)
		(unit 1)
		(exclude_from_sim no)
		(in_bom no)
		(on_board yes)
		(dnp yes)
		(fields_autoplaced yes)
		(property "Reference" "Q23"
			(at 300.99 115.57 90)
			(effects
				(font
					(size 1.27 1.27)
					(thickness 0.15)
				)
			)
		)
		(property "Value" "SISS05DN-T1-GE3"
			(at 313.69 113.03 0)
			(effects
				(font
					(size 1.27 1.27)
					(thickness 0.15)
				)
				(justify left bottom)
				(hide yes)
			)
		)
		(property "Footprint" "antmicro-footprints:Vishay_PowerPAK_1212-8_Single"
			(at 316.23 113.03 0)
			(effects
				(font
					(size 1.27 1.27)
					(thickness 0.15)
				)
				(justify left bottom)
				(hide yes)
			)
		)
		(property "Datasheet" "https://www.vishay.com/docs/77029/siss05dn.pdf"
			(at 318.77 113.03 0)
			(effects
				(font
					(size 1.27 1.27)
					(thickness 0.15)
				)
				(justify left bottom)
				(hide yes)
			)
		)
		(property "Description" "Power MOSFET, P Channel, 30 V, 108 A, 0.0035 ohm, PowerPAK 1212, Surface Mount"
			(at 321.31 113.03 0)
			(effects
				(font
					(size 1.27 1.27)
					(thickness 0.15)
				)
				(justify left bottom)
				(hide yes)
			)
		)
		(property "MPN" "SISS05DN-T1-GE3"
			(at 300.99 118.11 90)
			(effects
				(font
					(size 1.27 1.27)
					(thickness 0.15)
				)
			)
		)
		(property "Manufacturer" "Vishay"
			(at 323.85 113.03 0)
			(effects
				(font
					(size 1.27 1.27)
					(thickness 0.15)
				)
				(justify left bottom)
				(hide yes)
			)
		)
		(property "Author" "Antmicro"
			(at 326.39 113.03 0)
			(effects
				(font
					(size 1.27 1.27)
					(thickness 0.15)
				)
				(justify left bottom)
				(hide yes)
			)
		)
		(property "License" "Apache-2.0"
			(at 328.93 113.03 0)
			(effects
				(font
					(size 1.27 1.27)
					(thickness 0.15)
				)
				(justify left bottom)
				(hide yes)
			)
		)
		(pin "1"
		)
		(pin "4"
		)
		(pin "3"
		)
		(pin "5"
		)
		(pin "2"
		)
		(instances
			(project "jetson-agx-thor-baseboard"
				(path ""
					(reference "Q23")
					(unit 1)
				)
			)
		)
	)
	(symbol
		(lib_id "antmicropower:GND")
		(at 279.4 217.17 0)
		(unit 1)
		(exclude_from_sim no)
		(in_bom yes)
		(on_board yes)
		(dnp no)
		(property "Reference" "#PWR0515"
			(at 279.4 223.52 0)
			(effects
				(font
					(size 1.27 1.27)
				)
				(justify left bottom)
				(hide yes)
			)
		)
		(property "Value" "GND"
			(at 279.4 220.98 0)
			(effects
				(font
					(size 1.27 1.27)
					(thickness 0.15)
				)
			)
		)
		(property "Footprint" ""
			(at 288.29 224.79 0)
			(effects
				(font
					(size 1.27 1.27)
					(thickness 0.15)
				)
				(justify left bottom)
				(hide yes)
			)
		)
		(property "Datasheet" ""
			(at 288.29 229.87 0)
			(effects
				(font
					(size 1.27 1.27)
					(thickness 0.15)
				)
				(justify left bottom)
				(hide yes)
			)
		)
		(property "Description" ""
			(at 279.4 217.17 0)
			(effects
				(font
					(size 1.27 1.27)
				)
				(hide yes)
			)
		)
		(property "Author" "Antmicro"
			(at 288.29 224.79 0)
			(effects
				(font
					(size 1.27 1.27)
					(thickness 0.15)
				)
				(justify left bottom)
				(hide yes)
			)
		)
		(property "License" "Apache-2.0"
			(at 288.29 227.33 0)
			(effects
				(font
					(size 1.27 1.27)
					(thickness 0.15)
				)
				(justify left bottom)
				(hide yes)
			)
		)
		(pin "1"
		)
		(instances
			(project "jetson-agx-thor-baseboard"
				(path ""
					(reference "#PWR0515")
					(unit 1)
				)
			)
		)
	)
	(symbol
		(lib_id "antmicropower:+3V3_AON")
		(at 130.81 80.01 0)
		(unit 1)
		(exclude_from_sim no)
		(in_bom yes)
		(on_board yes)
		(dnp no)
		(fields_autoplaced yes)
		(property "Reference" "#PWR0163"
			(at 130.81 83.82 0)
			(effects
				(font
					(size 1.27 1.27)
				)
				(hide yes)
			)
		)
		(property "Value" "+3V3_AON"
			(at 130.81 74.93 0)
			(effects
				(font
					(size 1.27 1.27)
				)
			)
		)
		(property "Footprint" ""
			(at 130.81 80.01 0)
			(effects
				(font
					(size 1.27 1.27)
				)
				(hide yes)
			)
		)
		(property "Datasheet" ""
			(at 130.81 80.01 0)
			(effects
				(font
					(size 1.27 1.27)
				)
				(hide yes)
			)
		)
		(property "Description" ""
			(at 130.81 80.01 0)
			(effects
				(font
					(size 1.27 1.27)
				)
				(hide yes)
			)
		)
		(pin "1"
		)
		(instances
			(project "jetson-agx-thor-baseboard"
				(path ""
					(reference "#PWR0163")
					(unit 1)
				)
			)
		)
	)
	(symbol
		(lib_id "antmicropower:GND")
		(at 356.87 116.84 0)
		(unit 1)
		(exclude_from_sim no)
		(in_bom yes)
		(on_board yes)
		(dnp no)
		(property "Reference" "#PWR0612"
			(at 356.87 123.19 0)
			(effects
				(font
					(size 1.27 1.27)
				)
				(justify left bottom)
				(hide yes)
			)
		)
		(property "Value" "GND"
			(at 356.87 120.65 0)
			(effects
				(font
					(size 1.27 1.27)
					(thickness 0.15)
				)
			)
		)
		(property "Footprint" ""
			(at 365.76 124.46 0)
			(effects
				(font
					(size 1.27 1.27)
					(thickness 0.15)
				)
				(justify left bottom)
				(hide yes)
			)
		)
		(property "Datasheet" ""
			(at 365.76 129.54 0)
			(effects
				(font
					(size 1.27 1.27)
					(thickness 0.15)
				)
				(justify left bottom)
				(hide yes)
			)
		)
		(property "Description" ""
			(at 356.87 116.84 0)
			(effects
				(font
					(size 1.27 1.27)
				)
				(hide yes)
			)
		)
		(property "Author" "Antmicro"
			(at 365.76 124.46 0)
			(effects
				(font
					(size 1.27 1.27)
					(thickness 0.15)
				)
				(justify left bottom)
				(hide yes)
			)
		)
		(property "License" "Apache-2.0"
			(at 365.76 127 0)
			(effects
				(font
					(size 1.27 1.27)
					(thickness 0.15)
				)
				(justify left bottom)
				(hide yes)
			)
		)
		(pin "1"
		)
		(instances
			(project "jetson-agx-thor-baseboard"
				(path ""
					(reference "#PWR0612")
					(unit 1)
				)
			)
		)
	)
	(symbol
		(lib_id "antmicroTestPoints:TP_0.75mm_SMD")
		(at 384.81 99.06 0)
		(unit 1)
		(exclude_from_sim no)
		(in_bom no)
		(on_board yes)
		(dnp no)
		(property "Reference" "TP124"
			(at 389.255 99.06 0)
			(effects
				(font
					(size 1.27 1.27)
				)
				(justify left)
			)
		)
		(property "Value" "TP_0.75mm_SMD"
			(at 394.97 102.87 0)
			(effects
				(font
					(size 1.27 1.27)
					(thickness 0.15)
				)
				(justify left bottom)
				(hide yes)
			)
		)
		(property "Footprint" "antmicro-footprints:TP_SMD_0.75mm"
			(at 394.97 105.41 0)
			(effects
				(font
					(size 1.27 1.27)
					(thickness 0.15)
				)
				(justify left bottom)
				(hide yes)
			)
		)
		(property "Datasheet" ""
			(at 402.59 111.76 0)
			(effects
				(font
					(size 1.27 1.27)
					(thickness 0.15)
				)
				(justify left bottom)
				(hide yes)
			)
		)
		(property "Description" "SMT test point"
			(at 384.81 99.06 0)
			(effects
				(font
					(size 1.27 1.27)
				)
				(hide yes)
			)
		)
		(property "MPN" ""
			(at 395.605 110.49 0)
			(effects
				(font
					(size 1.27 1.27)
					(thickness 0.15)
				)
				(justify left bottom)
				(hide yes)
			)
		)
		(property "Manufacturer" ""
			(at 395.605 105.41 0)
			(effects
				(font
					(size 1.27 1.27)
					(thickness 0.15)
				)
				(justify left bottom)
				(hide yes)
			)
		)
		(property "Author" "Antmicro"
			(at 394.97 107.95 0)
			(effects
				(font
					(size 1.27 1.27)
					(thickness 0.15)
				)
				(justify left bottom)
				(hide yes)
			)
		)
		(property "License" "Apache-2.0"
			(at 394.97 110.49 0)
			(effects
				(font
					(size 1.27 1.27)
					(thickness 0.15)
				)
				(justify left bottom)
				(hide yes)
			)
		)
		(pin "1"
		)
		(instances
			(project "jetson-agx-thor-baseboard"
				(path ""
					(reference "TP124")
					(unit 1)
				)
			)
		)
	)
	(symbol
		(lib_id "antmicroLEDIndicationDiscrete:LED_G_0603_LTST-C190GKT")
		(at 269.24 215.9 90)
		(unit 1)
		(exclude_from_sim no)
		(in_bom yes)
		(on_board yes)
		(dnp no)
		(property "Reference" "D61"
			(at 270.51 212.09 90)
			(effects
				(font
					(size 1.27 1.27)
				)
				(justify right)
			)
		)
		(property "Value" "LED_G_0603_LTST-C190GKT"
			(at 276.86 193.04 0)
			(effects
				(font
					(size 1.27 1.27)
					(thickness 0.15)
				)
				(justify left bottom)
				(hide yes)
			)
		)
		(property "Footprint" "antmicro-footprints:LED_0603_1608Metric_G"
			(at 279.4 193.04 0)
			(effects
				(font
					(size 1.27 1.27)
					(thickness 0.15)
				)
				(justify left bottom)
				(hide yes)
			)
		)
		(property "Datasheet" "https://media.digikey.com/pdf/Data%20Sheets/Lite-On%20PDFs/LTST-C190GKT.pdf"
			(at 281.94 193.04 0)
			(effects
				(font
					(size 1.27 1.27)
					(thickness 0.15)
				)
				(justify left bottom)
				(hide yes)
			)
		)
		(property "Description" "LED, Green, SMD, 0603, 20 mA, 2.1 V, 569 nm"
			(at 269.24 215.9 0)
			(effects
				(font
					(size 1.27 1.27)
				)
				(hide yes)
			)
		)
		(property "MPN" "LTST-C190GKT"
			(at 284.48 193.04 0)
			(effects
				(font
					(size 1.27 1.27)
					(thickness 0.15)
				)
				(justify left bottom)
				(hide yes)
			)
		)
		(property "Manufacturer" "Lite-On"
			(at 287.02 193.04 0)
			(effects
				(font
					(size 1.27 1.27)
					(thickness 0.15)
				)
				(justify left bottom)
				(hide yes)
			)
		)
		(property "Author" "Antmicro"
			(at 289.56 193.04 0)
			(effects
				(font
					(size 1.27 1.27)
					(thickness 0.15)
				)
				(justify left bottom)
				(hide yes)
			)
		)
		(property "License" "Apache-2.0"
			(at 292.1 193.04 0)
			(effects
				(font
					(size 1.27 1.27)
					(thickness 0.15)
				)
				(justify left bottom)
				(hide yes)
			)
		)
		(property "Color" "Green"
			(at 270.51 214.63 90)
			(effects
				(font
					(size 1.27 1.27)
				)
				(justify right)
			)
		)
		(pin "1"
		)
		(pin "2"
		)
		(instances
			(project "jetson-agx-thor-baseboard"
				(path ""
					(reference "D61")
					(unit 1)
				)
			)
		)
	)
	(symbol
		(lib_id "antmicroLEDIndicationDiscrete:LED_G_0603_LTST-C190GKT")
		(at 345.44 201.93 90)
		(unit 1)
		(exclude_from_sim no)
		(in_bom yes)
		(on_board yes)
		(dnp no)
		(property "Reference" "D43"
			(at 346.71 198.12 90)
			(effects
				(font
					(size 1.27 1.27)
				)
				(justify right)
			)
		)
		(property "Value" "LED_G_0603_LTST-C190GKT"
			(at 353.06 179.07 0)
			(effects
				(font
					(size 1.27 1.27)
					(thickness 0.15)
				)
				(justify left bottom)
				(hide yes)
			)
		)
		(property "Footprint" "antmicro-footprints:LED_0603_1608Metric_G"
			(at 355.6 179.07 0)
			(effects
				(font
					(size 1.27 1.27)
					(thickness 0.15)
				)
				(justify left bottom)
				(hide yes)
			)
		)
		(property "Datasheet" "https://media.digikey.com/pdf/Data%20Sheets/Lite-On%20PDFs/LTST-C190GKT.pdf"
			(at 358.14 179.07 0)
			(effects
				(font
					(size 1.27 1.27)
					(thickness 0.15)
				)
				(justify left bottom)
				(hide yes)
			)
		)
		(property "Description" "LED, Green, SMD, 0603, 20 mA, 2.1 V, 569 nm"
			(at 345.44 201.93 0)
			(effects
				(font
					(size 1.27 1.27)
				)
				(hide yes)
			)
		)
		(property "MPN" "LTST-C190GKT"
			(at 360.68 179.07 0)
			(effects
				(font
					(size 1.27 1.27)
					(thickness 0.15)
				)
				(justify left bottom)
				(hide yes)
			)
		)
		(property "Manufacturer" "Lite-On"
			(at 363.22 179.07 0)
			(effects
				(font
					(size 1.27 1.27)
					(thickness 0.15)
				)
				(justify left bottom)
				(hide yes)
			)
		)
		(property "Author" "Antmicro"
			(at 365.76 179.07 0)
			(effects
				(font
					(size 1.27 1.27)
					(thickness 0.15)
				)
				(justify left bottom)
				(hide yes)
			)
		)
		(property "License" "Apache-2.0"
			(at 368.3 179.07 0)
			(effects
				(font
					(size 1.27 1.27)
					(thickness 0.15)
				)
				(justify left bottom)
				(hide yes)
			)
		)
		(property "Color" "Green"
			(at 346.71 200.66 90)
			(effects
				(font
					(size 1.27 1.27)
				)
				(justify right)
			)
		)
		(pin "1"
		)
		(pin "2"
		)
		(instances
			(project "jetson-agx-thor-baseboard"
				(path ""
					(reference "D43")
					(unit 1)
				)
			)
		)
	)
	(symbol
		(lib_id "antmicropower:GND")
		(at 101.6 96.52 0)
		(mirror y)
		(unit 1)
		(exclude_from_sim no)
		(in_bom yes)
		(on_board yes)
		(dnp no)
		(property "Reference" "#PWR0139"
			(at 101.6 102.87 0)
			(effects
				(font
					(size 1.27 1.27)
				)
				(justify left bottom)
				(hide yes)
			)
		)
		(property "Value" "GND"
			(at 101.6 100.33 0)
			(effects
				(font
					(size 1.27 1.27)
					(thickness 0.15)
				)
			)
		)
		(property "Footprint" ""
			(at 92.71 104.14 0)
			(effects
				(font
					(size 1.27 1.27)
					(thickness 0.15)
				)
				(justify left bottom)
				(hide yes)
			)
		)
		(property "Datasheet" ""
			(at 92.71 109.22 0)
			(effects
				(font
					(size 1.27 1.27)
					(thickness 0.15)
				)
				(justify left bottom)
				(hide yes)
			)
		)
		(property "Description" ""
			(at 101.6 96.52 0)
			(effects
				(font
					(size 1.27 1.27)
				)
				(hide yes)
			)
		)
		(property "Author" "Antmicro"
			(at 92.71 104.14 0)
			(effects
				(font
					(size 1.27 1.27)
					(thickness 0.15)
				)
				(justify left bottom)
				(hide yes)
			)
		)
		(property "License" "Apache-2.0"
			(at 92.71 106.68 0)
			(effects
				(font
					(size 1.27 1.27)
					(thickness 0.15)
				)
				(justify left bottom)
				(hide yes)
			)
		)
		(pin "1"
		)
		(instances
			(project "jetson-agx-thor-baseboard"
				(path ""
					(reference "#PWR0139")
					(unit 1)
				)
			)
		)
	)
	(symbol
		(lib_id "antmicroLEDIndicationDiscrete:LED_G_0603_LTST-C190GKT")
		(at 238.76 215.9 90)
		(unit 1)
		(exclude_from_sim no)
		(in_bom yes)
		(on_board yes)
		(dnp no)
		(property "Reference" "D4"
			(at 240.03 212.09 90)
			(effects
				(font
					(size 1.27 1.27)
				)
				(justify right)
			)
		)
		(property "Value" "LED_G_0603_LTST-C190GKT"
			(at 246.38 193.04 0)
			(effects
				(font
					(size 1.27 1.27)
					(thickness 0.15)
				)
				(justify left bottom)
				(hide yes)
			)
		)
		(property "Footprint" "antmicro-footprints:LED_0603_1608Metric_G"
			(at 248.92 193.04 0)
			(effects
				(font
					(size 1.27 1.27)
					(thickness 0.15)
				)
				(justify left bottom)
				(hide yes)
			)
		)
		(property "Datasheet" "https://media.digikey.com/pdf/Data%20Sheets/Lite-On%20PDFs/LTST-C190GKT.pdf"
			(at 251.46 193.04 0)
			(effects
				(font
					(size 1.27 1.27)
					(thickness 0.15)
				)
				(justify left bottom)
				(hide yes)
			)
		)
		(property "Description" "LED, Green, SMD, 0603, 20 mA, 2.1 V, 569 nm"
			(at 238.76 215.9 0)
			(effects
				(font
					(size 1.27 1.27)
				)
				(hide yes)
			)
		)
		(property "MPN" "LTST-C190GKT"
			(at 254 193.04 0)
			(effects
				(font
					(size 1.27 1.27)
					(thickness 0.15)
				)
				(justify left bottom)
				(hide yes)
			)
		)
		(property "Manufacturer" "Lite-On"
			(at 256.54 193.04 0)
			(effects
				(font
					(size 1.27 1.27)
					(thickness 0.15)
				)
				(justify left bottom)
				(hide yes)
			)
		)
		(property "Author" "Antmicro"
			(at 259.08 193.04 0)
			(effects
				(font
					(size 1.27 1.27)
					(thickness 0.15)
				)
				(justify left bottom)
				(hide yes)
			)
		)
		(property "License" "Apache-2.0"
			(at 261.62 193.04 0)
			(effects
				(font
					(size 1.27 1.27)
					(thickness 0.15)
				)
				(justify left bottom)
				(hide yes)
			)
		)
		(property "Color" "Green"
			(at 240.03 214.63 90)
			(effects
				(font
					(size 1.27 1.27)
				)
				(justify right)
			)
		)
		(pin "1"
		)
		(pin "2"
		)
		(instances
			(project "jetson-agx-thor-baseboard"
				(path ""
					(reference "D4")
					(unit 1)
				)
			)
		)
	)
	(symbol
		(lib_id "antmicroResistors0603:R_0R_22.4A_0603")
		(at 116.84 81.28 0)
		(unit 1)
		(exclude_from_sim no)
		(in_bom yes)
		(on_board yes)
		(dnp no)
		(property "Reference" "R63"
			(at 119.38 76.962 0)
			(effects
				(font
					(size 1.27 1.27)
				)
			)
		)
		(property "Value" "R_0R_22.4A_0603"
			(at 119.38 72.39 0)
			(effects
				(font
					(size 1.27 1.27)
					(thickness 0.15)
				)
				(hide yes)
			)
		)
		(property "Footprint" "antmicro-footprints:R_0603_1608Metric"
			(at 132.08 91.44 0)
			(effects
				(font
					(size 1.27 1.27)
					(thickness 0.15)
				)
				(justify left bottom)
				(hide yes)
			)
		)
		(property "Datasheet" "https://fscdn.rohm.com/en/products/databook/datasheet/passive/resistor/chip_resistor/pmr-jpw-e.pdf"
			(at 132.08 93.98 0)
			(effects
				(font
					(size 1.27 1.27)
					(thickness 0.15)
				)
				(justify left bottom)
				(hide yes)
			)
		)
		(property "Description" "SMD Chip Resistor"
			(at 116.84 81.28 0)
			(effects
				(font
					(size 1.27 1.27)
				)
				(hide yes)
			)
		)
		(property "Manufacturer" "ROHM Semiconductor"
			(at 132.08 99.06 0)
			(effects
				(font
					(size 1.27 1.27)
					(thickness 0.15)
				)
				(justify left bottom)
				(hide yes)
			)
		)
		(property "MPN" "PMR03EZPJ000"
			(at 132.08 96.52 0)
			(effects
				(font
					(size 1.27 1.27)
					(thickness 0.15)
				)
				(justify left bottom)
				(hide yes)
			)
		)
		(property "Val" "0R"
			(at 119.38 78.74 0)
			(effects
				(font
					(size 1.27 1.27)
					(thickness 0.15)
				)
			)
		)
		(property "Author" "Antmicro"
			(at 132.08 104.14 0)
			(effects
				(font
					(size 1.27 1.27)
					(thickness 0.15)
				)
				(justify left bottom)
				(hide yes)
			)
		)
		(property "License" "Apache-2.0"
			(at 132.08 106.68 0)
			(effects
				(font
					(size 1.27 1.27)
					(thickness 0.15)
				)
				(justify left bottom)
				(hide yes)
			)
		)
		(property "Max. Curr." "22.4A"
			(at 119.38 83.82 0)
			(effects
				(font
					(size 1.27 1.27)
					(thickness 0.15)
				)
			)
		)
		(property "Tolerance" "template_tolerance"
			(at 137.16 91.44 0)
			(effects
				(font
					(size 1.27 1.27)
				)
				(justify left bottom)
				(hide yes)
			)
		)
		(pin "1"
		)
		(pin "2"
		)
		(instances
			(project "jetson-agx-thor-baseboard"
				(path ""
					(reference "R63")
					(unit 1)
				)
			)
		)
	)
	(symbol
		(lib_id "antmicropower:+5V")
		(at 345.44 189.23 0)
		(unit 1)
		(exclude_from_sim no)
		(in_bom yes)
		(on_board yes)
		(dnp no)
		(property "Reference" "#PWR0513"
			(at 345.44 193.04 0)
			(effects
				(font
					(size 1.27 1.27)
				)
				(justify left bottom)
				(hide yes)
			)
		)
		(property "Value" "+5V"
			(at 345.44 185.42 0)
			(effects
				(font
					(size 1.27 1.27)
					(thickness 0.15)
				)
			)
		)
		(property "Footprint" ""
			(at 360.68 196.85 0)
			(effects
				(font
					(size 1.27 1.27)
					(thickness 0.15)
				)
				(justify left bottom)
				(hide yes)
			)
		)
		(property "Datasheet" ""
			(at 360.68 199.39 0)
			(effects
				(font
					(size 1.27 1.27)
					(thickness 0.15)
				)
				(justify left bottom)
				(hide yes)
			)
		)
		(property "Description" ""
			(at 345.44 189.23 0)
			(effects
				(font
					(size 1.27 1.27)
				)
				(hide yes)
			)
		)
		(property "Author" "Antmicro"
			(at 360.68 196.85 0)
			(effects
				(font
					(size 1.27 1.27)
					(thickness 0.15)
				)
				(justify left bottom)
				(hide yes)
			)
		)
		(property "License" "Apache-2.0"
			(at 360.68 199.39 0)
			(effects
				(font
					(size 1.27 1.27)
					(thickness 0.15)
				)
				(justify left bottom)
				(hide yes)
			)
		)
		(pin "1"
		)
		(instances
			(project "jetson-agx-thor-baseboard"
				(path ""
					(reference "#PWR0513")
					(unit 1)
				)
			)
		)
	)
	(symbol
		(lib_id "antmicroTransistorsFETsMOSFETsSingle:SISS05DN-T1-GE3")
		(at 302.26 41.91 270)
		(mirror x)
		(unit 1)
		(exclude_from_sim no)
		(in_bom yes)
		(on_board yes)
		(dnp no)
		(property "Reference" "Q41"
			(at 304.546 29.718 90)
			(effects
				(font
					(size 1.27 1.27)
					(thickness 0.15)
				)
			)
		)
		(property "Value" "SISS05DN-T1-GE3"
			(at 292.1 26.67 0)
			(effects
				(font
					(size 1.27 1.27)
					(thickness 0.15)
				)
				(justify left bottom)
				(hide yes)
			)
		)
		(property "Footprint" "antmicro-footprints:Vishay_PowerPAK_1212-8_Single"
			(at 289.56 26.67 0)
			(effects
				(font
					(size 1.27 1.27)
					(thickness 0.15)
				)
				(justify left bottom)
				(hide yes)
			)
		)
		(property "Datasheet" "https://www.vishay.com/docs/77029/siss05dn.pdf"
			(at 287.02 26.67 0)
			(effects
				(font
					(size 1.27 1.27)
					(thickness 0.15)
				)
				(justify left bottom)
				(hide yes)
			)
		)
		(property "Description" "Power MOSFET, P Channel, 30 V, 108 A, 0.0035 ohm, PowerPAK 1212, Surface Mount"
			(at 284.48 26.67 0)
			(effects
				(font
					(size 1.27 1.27)
					(thickness 0.15)
				)
				(justify left bottom)
				(hide yes)
			)
		)
		(property "MPN" "SISS05DN-T1-GE3"
			(at 304.546 32.258 90)
			(effects
				(font
					(size 1.27 1.27)
					(thickness 0.15)
				)
			)
		)
		(property "Manufacturer" "Vishay"
			(at 281.94 26.67 0)
			(effects
				(font
					(size 1.27 1.27)
					(thickness 0.15)
				)
				(justify left bottom)
				(hide yes)
			)
		)
		(property "Author" "Antmicro"
			(at 279.4 26.67 0)
			(effects
				(font
					(size 1.27 1.27)
					(thickness 0.15)
				)
				(justify left bottom)
				(hide yes)
			)
		)
		(property "License" "Apache-2.0"
			(at 276.86 26.67 0)
			(effects
				(font
					(size 1.27 1.27)
					(thickness 0.15)
				)
				(justify left bottom)
				(hide yes)
			)
		)
		(pin "1"
		)
		(pin "4"
		)
		(pin "3"
		)
		(pin "5"
		)
		(pin "2"
		)
		(instances
			(project "jetson-agx-thor-baseboard"
				(path ""
					(reference "Q41")
					(unit 1)
				)
			)
		)
	)
	(symbol
		(lib_id "antmicroResistors0402:R_10k_0402")
		(at 368.3 217.17 90)
		(unit 1)
		(exclude_from_sim no)
		(in_bom yes)
		(on_board yes)
		(dnp no)
		(property "Reference" "R72"
			(at 361.95 213.106 90)
			(effects
				(font
					(size 1.27 1.27)
				)
				(justify right)
			)
		)
		(property "Value" "R_10k_0402"
			(at 381 196.85 0)
			(effects
				(font
					(size 1.27 1.27)
					(thickness 0.15)
				)
				(justify left bottom)
				(hide yes)
			)
		)
		(property "Footprint" "antmicro-footprints:R_0402_1005Metric"
			(at 383.54 196.85 0)
			(effects
				(font
					(size 1.27 1.27)
					(thickness 0.15)
				)
				(justify left bottom)
				(hide yes)
			)
		)
		(property "Datasheet" "https://www.bourns.com/docs/product-datasheets/cr.pdf"
			(at 386.08 196.85 0)
			(effects
				(font
					(size 1.27 1.27)
					(thickness 0.15)
				)
				(justify left bottom)
				(hide yes)
			)
		)
		(property "Description" "SMD Chip Resistor, 10 kohm, ± 1%, 62.5 mW, 0402 [1005 Metric], Thick Film, General Purpose"
			(at 368.3 217.17 0)
			(effects
				(font
					(size 1.27 1.27)
				)
				(hide yes)
			)
		)
		(property "Manufacturer" "Bourns"
			(at 391.16 196.85 0)
			(effects
				(font
					(size 1.27 1.27)
					(thickness 0.15)
				)
				(justify left bottom)
				(hide yes)
			)
		)
		(property "MPN" "CR0402-FX-1002GLF"
			(at 388.62 196.85 0)
			(effects
				(font
					(size 1.27 1.27)
					(thickness 0.15)
				)
				(justify left bottom)
				(hide yes)
			)
		)
		(property "Val" "10k"
			(at 361.95 215.646 90)
			(effects
				(font
					(size 1.27 1.27)
					(thickness 0.15)
				)
				(justify right)
			)
		)
		(property "License" "Apache-2.0"
			(at 393.7 196.85 0)
			(effects
				(font
					(size 1.27 1.27)
					(thickness 0.15)
				)
				(justify left bottom)
				(hide yes)
			)
		)
		(property "Author" "Antmicro"
			(at 396.24 196.85 0)
			(effects
				(font
					(size 1.27 1.27)
					(thickness 0.15)
				)
				(justify left bottom)
				(hide yes)
			)
		)
		(property "Tolerance" "1%"
			(at 378.46 196.85 0)
			(effects
				(font
					(size 1.27 1.27)
				)
				(justify left bottom)
				(hide yes)
			)
		)
		(pin "1"
		)
		(pin "2"
		)
		(instances
			(project "jetson-agx-thor-baseboard"
				(path ""
					(reference "R72")
					(unit 1)
				)
			)
		)
	)
	(symbol
		(lib_id "antmicroCapacitors0402:C_1u_25V_0402")
		(at 308.61 144.78 90)
		(unit 1)
		(exclude_from_sim no)
		(in_bom no)
		(on_board yes)
		(dnp yes)
		(fields_autoplaced yes)
		(property "Reference" "C262"
			(at 311.15 140.9636 90)
			(effects
				(font
					(size 1.27 1.27)
					(thickness 0.15)
				)
				(justify right)
			)
		)
		(property "Value" "C_1u_25V_0402"
			(at 318.77 124.46 0)
			(effects
				(font
					(size 1.27 1.27)
					(thickness 0.15)
				)
				(justify left bottom)
				(hide yes)
			)
		)
		(property "Footprint" "antmicro-footprints:C_0402_1005Metric"
			(at 321.31 124.46 0)
			(effects
				(font
					(size 1.27 1.27)
					(thickness 0.15)
				)
				(justify left bottom)
				(hide yes)
			)
		)
		(property "Datasheet" "https://www.murata.com/products/productdetail?partno=GRM155R61E105KE11%23"
			(at 323.85 124.46 0)
			(effects
				(font
					(size 1.27 1.27)
					(thickness 0.15)
				)
				(justify left bottom)
				(hide yes)
			)
		)
		(property "Description" "SMD Multilayer Ceramic Capacitor, 1 µF, 25 V, 0402 [1005 Metric], ± 10%, X5R, GRM Series"
			(at 308.61 144.78 0)
			(effects
				(font
					(size 1.27 1.27)
				)
				(hide yes)
			)
		)
		(property "MPN" "GRM155R61E105KE11J"
			(at 326.39 124.46 0)
			(effects
				(font
					(size 1.27 1.27)
					(thickness 0.15)
				)
				(justify left bottom)
				(hide yes)
			)
		)
		(property "Manufacturer" "Murata"
			(at 328.93 124.46 0)
			(effects
				(font
					(size 1.27 1.27)
					(thickness 0.15)
				)
				(justify left bottom)
				(hide yes)
			)
		)
		(property "License" "Apache-2.0"
			(at 331.47 124.46 0)
			(effects
				(font
					(size 1.27 1.27)
					(thickness 0.15)
				)
				(justify left bottom)
				(hide yes)
			)
		)
		(property "Author" "Antmicro"
			(at 334.01 124.46 0)
			(effects
				(font
					(size 1.27 1.27)
					(thickness 0.15)
				)
				(justify left bottom)
				(hide yes)
			)
		)
		(property "Val" "1u"
			(at 311.15 143.5036 90)
			(effects
				(font
					(size 1.27 1.27)
					(thickness 0.15)
				)
				(justify right)
			)
		)
		(property "Voltage" "25V"
			(at 336.55 124.46 0)
			(effects
				(font
					(size 1.27 1.27)
				)
				(justify left bottom)
				(hide yes)
			)
		)
		(property "Dielectric" "X5R"
			(at 339.09 124.46 0)
			(effects
				(font
					(size 1.27 1.27)
				)
				(justify left bottom)
				(hide yes)
			)
		)
		(pin "1"
		)
		(pin "2"
		)
		(instances
			(project "jetson-agx-thor-baseboard"
				(path ""
					(reference "C262")
					(unit 1)
				)
			)
		)
	)
	(symbol
		(lib_id "antmicroCapacitors0402:C_1u_25V_0402")
		(at 383.54 80.01 90)
		(unit 1)
		(exclude_from_sim no)
		(in_bom yes)
		(on_board yes)
		(dnp no)
		(fields_autoplaced yes)
		(property "Reference" "C265"
			(at 386.08 76.1936 90)
			(effects
				(font
					(size 1.27 1.27)
					(thickness 0.15)
				)
				(justify right)
			)
		)
		(property "Value" "C_1u_25V_0402"
			(at 393.7 59.69 0)
			(effects
				(font
					(size 1.27 1.27)
					(thickness 0.15)
				)
				(justify left bottom)
				(hide yes)
			)
		)
		(property "Footprint" "antmicro-footprints:C_0402_1005Metric"
			(at 396.24 59.69 0)
			(effects
				(font
					(size 1.27 1.27)
					(thickness 0.15)
				)
				(justify left bottom)
				(hide yes)
			)
		)
		(property "Datasheet" "https://www.murata.com/products/productdetail?partno=GRM155R61E105KE11%23"
			(at 398.78 59.69 0)
			(effects
				(font
					(size 1.27 1.27)
					(thickness 0.15)
				)
				(justify left bottom)
				(hide yes)
			)
		)
		(property "Description" "SMD Multilayer Ceramic Capacitor, 1 µF, 25 V, 0402 [1005 Metric], ± 10%, X5R, GRM Series"
			(at 383.54 80.01 0)
			(effects
				(font
					(size 1.27 1.27)
				)
				(hide yes)
			)
		)
		(property "MPN" "GRM155R61E105KE11J"
			(at 401.32 59.69 0)
			(effects
				(font
					(size 1.27 1.27)
					(thickness 0.15)
				)
				(justify left bottom)
				(hide yes)
			)
		)
		(property "Manufacturer" "Murata"
			(at 403.86 59.69 0)
			(effects
				(font
					(size 1.27 1.27)
					(thickness 0.15)
				)
				(justify left bottom)
				(hide yes)
			)
		)
		(property "License" "Apache-2.0"
			(at 406.4 59.69 0)
			(effects
				(font
					(size 1.27 1.27)
					(thickness 0.15)
				)
				(justify left bottom)
				(hide yes)
			)
		)
		(property "Author" "Antmicro"
			(at 408.94 59.69 0)
			(effects
				(font
					(size 1.27 1.27)
					(thickness 0.15)
				)
				(justify left bottom)
				(hide yes)
			)
		)
		(property "Val" "1u"
			(at 386.08 78.7336 90)
			(effects
				(font
					(size 1.27 1.27)
					(thickness 0.15)
				)
				(justify right)
			)
		)
		(property "Voltage" "25V"
			(at 411.48 59.69 0)
			(effects
				(font
					(size 1.27 1.27)
				)
				(justify left bottom)
				(hide yes)
			)
		)
		(property "Dielectric" "X5R"
			(at 414.02 59.69 0)
			(effects
				(font
					(size 1.27 1.27)
				)
				(justify left bottom)
				(hide yes)
			)
		)
		(pin "1"
		)
		(pin "2"
		)
		(instances
			(project "jetson-agx-thor-baseboard"
				(path ""
					(reference "C265")
					(unit 1)
				)
			)
		)
	)
	(symbol
		(lib_id "antmicroResistors0402:R_31k6_0402")
		(at 101.6 87.63 270)
		(mirror x)
		(unit 1)
		(exclude_from_sim no)
		(in_bom yes)
		(on_board yes)
		(dnp no)
		(fields_autoplaced yes)
		(property "Reference" "R416"
			(at 99.06 83.82 90)
			(effects
				(font
					(size 1.27 1.27)
					(thickness 0.15)
				)
				(justify right)
			)
		)
		(property "Value" "R_31k6_0402"
			(at 88.9 67.31 0)
			(effects
				(font
					(size 1.27 1.27)
					(thickness 0.15)
				)
				(justify left bottom)
				(hide yes)
			)
		)
		(property "Footprint" "antmicro-footprints:R_0402_1005Metric"
			(at 86.36 67.31 0)
			(effects
				(font
					(size 1.27 1.27)
					(thickness 0.15)
				)
				(justify left bottom)
				(hide yes)
			)
		)
		(property "Datasheet" "https://www.bourns.com/docs/product-datasheets/cr.pdf"
			(at 83.82 67.31 0)
			(effects
				(font
					(size 1.27 1.27)
					(thickness 0.15)
				)
				(justify left bottom)
				(hide yes)
			)
		)
		(property "Description" "SMD Chip Resistor"
			(at 71.12 67.31 0)
			(effects
				(font
					(size 1.27 1.27)
				)
				(justify left bottom)
				(hide yes)
			)
		)
		(property "MPN" "CR0402-FX-3162GLF"
			(at 81.28 67.31 0)
			(effects
				(font
					(size 1.27 1.27)
					(thickness 0.15)
				)
				(justify left bottom)
				(hide yes)
			)
		)
		(property "Manufacturer" "Bourns"
			(at 78.74 67.31 0)
			(effects
				(font
					(size 1.27 1.27)
					(thickness 0.15)
				)
				(justify left bottom)
				(hide yes)
			)
		)
		(property "License" "Apache-2.0"
			(at 76.2 67.31 0)
			(effects
				(font
					(size 1.27 1.27)
					(thickness 0.15)
				)
				(justify left bottom)
				(hide yes)
			)
		)
		(property "Author" "Antmicro"
			(at 73.66 67.31 0)
			(effects
				(font
					(size 1.27 1.27)
					(thickness 0.15)
				)
				(justify left bottom)
				(hide yes)
			)
		)
		(property "Val" "31k6"
			(at 99.06 86.36 90)
			(effects
				(font
					(size 1.27 1.27)
					(thickness 0.15)
				)
				(justify right)
			)
		)
		(property "Tolerance" "1%"
			(at 91.44 67.31 0)
			(effects
				(font
					(size 1.27 1.27)
				)
				(justify left bottom)
				(hide yes)
			)
		)
		(pin "1"
		)
		(pin "2"
		)
		(instances
			(project ""
				(path ""
					(reference "R416")
					(unit 1)
				)
			)
		)
	)
	(symbol
		(lib_id "antmicroTestPoints:TP_0.75mm_SMD")
		(at 384.81 62.23 0)
		(unit 1)
		(exclude_from_sim no)
		(in_bom no)
		(on_board yes)
		(dnp no)
		(property "Reference" "TP123"
			(at 389.255 62.23 0)
			(effects
				(font
					(size 1.27 1.27)
				)
				(justify left)
			)
		)
		(property "Value" "TP_0.75mm_SMD"
			(at 394.97 66.04 0)
			(effects
				(font
					(size 1.27 1.27)
					(thickness 0.15)
				)
				(justify left bottom)
				(hide yes)
			)
		)
		(property "Footprint" "antmicro-footprints:TP_SMD_0.75mm"
			(at 394.97 68.58 0)
			(effects
				(font
					(size 1.27 1.27)
					(thickness 0.15)
				)
				(justify left bottom)
				(hide yes)
			)
		)
		(property "Datasheet" ""
			(at 402.59 74.93 0)
			(effects
				(font
					(size 1.27 1.27)
					(thickness 0.15)
				)
				(justify left bottom)
				(hide yes)
			)
		)
		(property "Description" "SMT test point"
			(at 384.81 62.23 0)
			(effects
				(font
					(size 1.27 1.27)
				)
				(hide yes)
			)
		)
		(property "MPN" ""
			(at 395.605 73.66 0)
			(effects
				(font
					(size 1.27 1.27)
					(thickness 0.15)
				)
				(justify left bottom)
				(hide yes)
			)
		)
		(property "Manufacturer" ""
			(at 395.605 68.58 0)
			(effects
				(font
					(size 1.27 1.27)
					(thickness 0.15)
				)
				(justify left bottom)
				(hide yes)
			)
		)
		(property "Author" "Antmicro"
			(at 394.97 71.12 0)
			(effects
				(font
					(size 1.27 1.27)
					(thickness 0.15)
				)
				(justify left bottom)
				(hide yes)
			)
		)
		(property "License" "Apache-2.0"
			(at 394.97 73.66 0)
			(effects
				(font
					(size 1.27 1.27)
					(thickness 0.15)
				)
				(justify left bottom)
				(hide yes)
			)
		)
		(pin "1"
		)
		(instances
			(project "jetson-agx-thor-baseboard"
				(path ""
					(reference "TP123")
					(unit 1)
				)
			)
		)
	)
	(symbol
		(lib_id "antmicropower:GND")
		(at 285.75 63.5 0)
		(unit 1)
		(exclude_from_sim no)
		(in_bom yes)
		(on_board yes)
		(dnp no)
		(property "Reference" "#PWR0634"
			(at 294.64 66.04 0)
			(effects
				(font
					(size 1.27 1.27)
					(thickness 0.15)
				)
				(justify left bottom)
				(hide yes)
			)
		)
		(property "Value" "GND"
			(at 285.75 67.31 0)
			(effects
				(font
					(size 1.27 1.27)
					(thickness 0.15)
				)
			)
		)
		(property "Footprint" ""
			(at 294.64 71.12 0)
			(effects
				(font
					(size 1.27 1.27)
					(thickness 0.15)
				)
				(justify left bottom)
				(hide yes)
			)
		)
		(property "Datasheet" ""
			(at 294.64 76.2 0)
			(effects
				(font
					(size 1.27 1.27)
					(thickness 0.15)
				)
				(justify left bottom)
				(hide yes)
			)
		)
		(property "Description" ""
			(at 294.64 78.74 0)
			(effects
				(font
					(size 1.27 1.27)
				)
				(justify left bottom)
				(hide yes)
			)
		)
		(property "Author" "Antmicro"
			(at 294.64 71.12 0)
			(effects
				(font
					(size 1.27 1.27)
					(thickness 0.15)
				)
				(justify left bottom)
				(hide yes)
			)
		)
		(property "License" "Apache-2.0"
			(at 294.64 73.66 0)
			(effects
				(font
					(size 1.27 1.27)
					(thickness 0.15)
				)
				(justify left bottom)
				(hide yes)
			)
		)
		(pin "1"
		)
		(instances
			(project "jetson-agx-thor-baseboard"
				(path ""
					(reference "#PWR0634")
					(unit 1)
				)
			)
		)
	)
	(symbol
		(lib_id "antmicroCapacitors0402:C_100n_0402")
		(at 351.79 114.3 90)
		(unit 1)
		(exclude_from_sim no)
		(in_bom yes)
		(on_board yes)
		(dnp no)
		(fields_autoplaced yes)
		(property "Reference" "C264"
			(at 349.25 110.4836 90)
			(effects
				(font
					(size 1.27 1.27)
					(thickness 0.15)
				)
				(justify left)
			)
		)
		(property "Value" "C_100n_0402"
			(at 374.65 99.06 0)
			(effects
				(font
					(size 1.27 1.27)
					(thickness 0.15)
				)
				(justify left bottom)
				(hide yes)
			)
		)
		(property "Footprint" "antmicro-footprints:C_0402_1005Metric"
			(at 377.19 99.06 0)
			(effects
				(font
					(size 1.27 1.27)
					(thickness 0.15)
				)
				(justify left bottom)
				(hide yes)
			)
		)
		(property "Datasheet" "https://www.murata.com/products/productdetail?partno=GRM155R61H104KE14%23"
			(at 379.73 99.06 0)
			(effects
				(font
					(size 1.27 1.27)
					(thickness 0.15)
				)
				(justify left bottom)
				(hide yes)
			)
		)
		(property "Description" "SMD Multilayer Ceramic Capacitor, 0.1 µF, 50 V, 0402 [1005 Metric], ± 10%, X5R, GRM Series"
			(at 351.79 114.3 0)
			(effects
				(font
					(size 1.27 1.27)
				)
				(hide yes)
			)
		)
		(property "MPN" "GRM155R61H104KE14D"
			(at 382.27 99.06 0)
			(effects
				(font
					(size 1.27 1.27)
					(thickness 0.15)
				)
				(justify left bottom)
				(hide yes)
			)
		)
		(property "Val" "100n"
			(at 349.25 113.0236 90)
			(effects
				(font
					(size 1.27 1.27)
					(thickness 0.15)
				)
				(justify left)
			)
		)
		(property "Voltage" "50V"
			(at 361.95 99.06 0)
			(effects
				(font
					(size 1.27 1.27)
					(thickness 0.15)
				)
				(justify left bottom)
				(hide yes)
			)
		)
		(property "Dielectric" "X5R"
			(at 364.49 99.06 0)
			(effects
				(font
					(size 1.27 1.27)
					(thickness 0.15)
				)
				(justify left bottom)
				(hide yes)
			)
		)
		(property "Manufacturer" "Murata"
			(at 367.03 99.06 0)
			(effects
				(font
					(size 1.27 1.27)
					(thickness 0.15)
				)
				(justify left bottom)
				(hide yes)
			)
		)
		(property "License" "Apache-2.0"
			(at 369.57 99.06 0)
			(effects
				(font
					(size 1.27 1.27)
					(thickness 0.15)
				)
				(justify left bottom)
				(hide yes)
			)
		)
		(property "Author" "Antmicro"
			(at 372.11 99.06 0)
			(effects
				(font
					(size 1.27 1.27)
					(thickness 0.15)
				)
				(justify left bottom)
				(hide yes)
			)
		)
		(pin "1"
		)
		(pin "2"
		)
		(instances
			(project "jetson-agx-thor-baseboard"
				(path ""
					(reference "C264")
					(unit 1)
				)
			)
		)
	)
	(symbol
		(lib_id "antmicroTestPoints:TP_0.75mm_SMD")
		(at 196.85 190.5 180)
		(unit 1)
		(exclude_from_sim no)
		(in_bom no)
		(on_board yes)
		(dnp no)
		(property "Reference" "TP128"
			(at 186.69 190.5 0)
			(effects
				(font
					(size 1.27 1.27)
				)
				(justify right)
			)
		)
		(property "Value" "TP_0.75mm_SMD"
			(at 186.69 186.69 0)
			(effects
				(font
					(size 1.27 1.27)
					(thickness 0.15)
				)
				(justify left bottom)
				(hide yes)
			)
		)
		(property "Footprint" "antmicro-footprints:TP_SMD_0.75mm"
			(at 186.69 184.15 0)
			(effects
				(font
					(size 1.27 1.27)
					(thickness 0.15)
				)
				(justify left bottom)
				(hide yes)
			)
		)
		(property "Datasheet" ""
			(at 179.07 177.8 0)
			(effects
				(font
					(size 1.27 1.27)
					(thickness 0.15)
				)
				(justify left bottom)
				(hide yes)
			)
		)
		(property "Description" "SMT test point"
			(at 196.85 190.5 0)
			(effects
				(font
					(size 1.27 1.27)
				)
				(hide yes)
			)
		)
		(property "MPN" ""
			(at 186.055 179.07 0)
			(effects
				(font
					(size 1.27 1.27)
					(thickness 0.15)
				)
				(justify left bottom)
				(hide yes)
			)
		)
		(property "Manufacturer" ""
			(at 186.055 184.15 0)
			(effects
				(font
					(size 1.27 1.27)
					(thickness 0.15)
				)
				(justify left bottom)
				(hide yes)
			)
		)
		(property "Author" "Antmicro"
			(at 186.69 181.61 0)
			(effects
				(font
					(size 1.27 1.27)
					(thickness 0.15)
				)
				(justify left bottom)
				(hide yes)
			)
		)
		(property "License" "Apache-2.0"
			(at 186.69 179.07 0)
			(effects
				(font
					(size 1.27 1.27)
					(thickness 0.15)
				)
				(justify left bottom)
				(hide yes)
			)
		)
		(pin "1"
		)
		(instances
			(project "jetson-agx-thor-baseboard"
				(path ""
					(reference "TP128")
					(unit 1)
				)
			)
		)
	)
	(symbol
		(lib_id "antmicropower:GND")
		(at 248.92 217.17 0)
		(unit 1)
		(exclude_from_sim no)
		(in_bom yes)
		(on_board yes)
		(dnp no)
		(property "Reference" "#PWR0673"
			(at 248.92 223.52 0)
			(effects
				(font
					(size 1.27 1.27)
				)
				(justify left bottom)
				(hide yes)
			)
		)
		(property "Value" "GND"
			(at 248.92 220.98 0)
			(effects
				(font
					(size 1.27 1.27)
					(thickness 0.15)
				)
			)
		)
		(property "Footprint" ""
			(at 257.81 224.79 0)
			(effects
				(font
					(size 1.27 1.27)
					(thickness 0.15)
				)
				(justify left bottom)
				(hide yes)
			)
		)
		(property "Datasheet" ""
			(at 257.81 229.87 0)
			(effects
				(font
					(size 1.27 1.27)
					(thickness 0.15)
				)
				(justify left bottom)
				(hide yes)
			)
		)
		(property "Description" ""
			(at 248.92 217.17 0)
			(effects
				(font
					(size 1.27 1.27)
				)
				(hide yes)
			)
		)
		(property "Author" "Antmicro"
			(at 257.81 224.79 0)
			(effects
				(font
					(size 1.27 1.27)
					(thickness 0.15)
				)
				(justify left bottom)
				(hide yes)
			)
		)
		(property "License" "Apache-2.0"
			(at 257.81 227.33 0)
			(effects
				(font
					(size 1.27 1.27)
					(thickness 0.15)
				)
				(justify left bottom)
				(hide yes)
			)
		)
		(pin "1"
		)
		(instances
			(project "jetson-agx-thor-baseboard"
				(path ""
					(reference "#PWR0673")
					(unit 1)
				)
			)
		)
	)
	(symbol
		(lib_id "antmicroResistors0402:R_232k_0402")
		(at 280.67 41.91 90)
		(unit 1)
		(exclude_from_sim no)
		(in_bom yes)
		(on_board yes)
		(dnp no)
		(property "Reference" "R409"
			(at 281.94 38.1 90)
			(effects
				(font
					(size 1.27 1.27)
					(thickness 0.15)
				)
				(justify right)
			)
		)
		(property "Value" "R_232k_0402"
			(at 293.37 21.59 0)
			(effects
				(font
					(size 1.27 1.27)
					(thickness 0.15)
				)
				(justify left bottom)
				(hide yes)
			)
		)
		(property "Footprint" "antmicro-footprints:R_0402_1005Metric"
			(at 295.91 21.59 0)
			(effects
				(font
					(size 1.27 1.27)
					(thickness 0.15)
				)
				(justify left bottom)
				(hide yes)
			)
		)
		(property "Datasheet" "https://www.mouser.com/datasheet/2/447/PYu_RT_1_to_0_01_RoHS_L_12-3003070.pdf"
			(at 298.45 21.59 0)
			(effects
				(font
					(size 1.27 1.27)
					(thickness 0.15)
				)
				(justify left bottom)
				(hide yes)
			)
		)
		(property "Description" "SMD Chip Resistor"
			(at 311.15 21.59 0)
			(effects
				(font
					(size 1.27 1.27)
				)
				(justify left bottom)
				(hide yes)
			)
		)
		(property "MPN" "RT0402FRE07232KL"
			(at 300.99 21.59 0)
			(effects
				(font
					(size 1.27 1.27)
					(thickness 0.15)
				)
				(justify left bottom)
				(hide yes)
			)
		)
		(property "Manufacturer" "YAGEO"
			(at 303.53 21.59 0)
			(effects
				(font
					(size 1.27 1.27)
					(thickness 0.15)
				)
				(justify left bottom)
				(hide yes)
			)
		)
		(property "License" "Apache-2.0"
			(at 306.07 21.59 0)
			(effects
				(font
					(size 1.27 1.27)
					(thickness 0.15)
				)
				(justify left bottom)
				(hide yes)
			)
		)
		(property "Author" "Antmicro"
			(at 308.61 21.59 0)
			(effects
				(font
					(size 1.27 1.27)
					(thickness 0.15)
				)
				(justify left bottom)
				(hide yes)
			)
		)
		(property "Val" "232k"
			(at 281.94 40.64 90)
			(effects
				(font
					(size 1.27 1.27)
					(thickness 0.15)
				)
				(justify right)
			)
		)
		(property "Tolerance" "1%"
			(at 290.83 21.59 0)
			(effects
				(font
					(size 1.27 1.27)
				)
				(justify left bottom)
				(hide yes)
			)
		)
		(pin "1"
		)
		(pin "2"
		)
		(instances
			(project ""
				(path ""
					(reference "R409")
					(unit 1)
				)
			)
		)
	)
	(symbol
		(lib_id "antmicroTransistorsFETsMOSFETsSingle:DMG1012T-7")
		(at 370.84 210.82 0)
		(unit 1)
		(exclude_from_sim no)
		(in_bom yes)
		(on_board yes)
		(dnp no)
		(fields_autoplaced yes)
		(property "Reference" "Q4"
			(at 381 207.01 0)
			(effects
				(font
					(size 1.27 1.27)
					(thickness 0.15)
				)
				(justify left)
			)
		)
		(property "Value" "DMG1012T-7"
			(at 393.7 219.71 0)
			(effects
				(font
					(size 1.27 1.27)
					(thickness 0.15)
				)
				(justify left bottom)
				(hide yes)
			)
		)
		(property "Footprint" "antmicro-footprints:SOT-523"
			(at 393.7 222.25 0)
			(effects
				(font
					(size 1.27 1.27)
					(thickness 0.15)
				)
				(justify left bottom)
				(hide yes)
			)
		)
		(property "Datasheet" "https://www.diodes.com/assets/Datasheets/ds31783.pdf"
			(at 393.7 224.79 0)
			(effects
				(font
					(size 1.27 1.27)
					(thickness 0.15)
				)
				(justify left bottom)
				(hide yes)
			)
		)
		(property "Description" "Power MOSFET, N Channel, 20 V, 630 mA, 0.3 ohm, SOT-523, Surface Mount"
			(at 393.7 237.49 0)
			(effects
				(font
					(size 1.27 1.27)
				)
				(justify left bottom)
				(hide yes)
			)
		)
		(property "MPN" "DMG1012T-7"
			(at 381 209.55 0)
			(effects
				(font
					(size 1.27 1.27)
					(thickness 0.15)
				)
				(justify left)
			)
		)
		(property "Manufacturer" "Diodes Incorporated"
			(at 393.7 229.87 0)
			(effects
				(font
					(size 1.27 1.27)
					(thickness 0.15)
				)
				(justify left bottom)
				(hide yes)
			)
		)
		(property "Author" "Antmicro"
			(at 393.7 232.41 0)
			(effects
				(font
					(size 1.27 1.27)
					(thickness 0.15)
				)
				(justify left bottom)
				(hide yes)
			)
		)
		(property "License" "Apache-2.0"
			(at 393.7 234.95 0)
			(effects
				(font
					(size 1.27 1.27)
					(thickness 0.15)
				)
				(justify left bottom)
				(hide yes)
			)
		)
		(pin "3"
		)
		(pin "2"
		)
		(pin "1"
		)
		(instances
			(project "jetson-agx-thor-baseboard"
				(path ""
					(reference "Q4")
					(unit 1)
				)
			)
		)
	)
	(symbol
		(lib_id "antmicroPMICORControllersIdealDiodes:LTC4412IS6")
		(at 284.48 99.06 0)
		(unit 1)
		(exclude_from_sim no)
		(in_bom no)
		(on_board yes)
		(dnp yes)
		(fields_autoplaced yes)
		(property "Reference" "U61"
			(at 293.37 91.44 0)
			(effects
				(font
					(size 1.27 1.27)
					(thickness 0.15)
				)
			)
		)
		(property "Value" "LTC4412IS6"
			(at 316.23 104.14 0)
			(effects
				(font
					(size 1.27 1.27)
					(thickness 0.15)
				)
				(justify left bottom)
				(hide yes)
			)
		)
		(property "Footprint" "antmicro-footprints:SOT-23-6"
			(at 316.23 106.68 0)
			(effects
				(font
					(size 1.27 1.27)
					(thickness 0.15)
				)
				(justify left bottom)
				(hide yes)
			)
		)
		(property "Datasheet" "https://www.analog.com/media/en/technical-documentation/data-sheets/4412fb.pdf"
			(at 316.23 109.22 0)
			(effects
				(font
					(size 1.27 1.27)
					(thickness 0.15)
				)
				(justify left bottom)
				(hide yes)
			)
		)
		(property "Description" "Ideal diode controller"
			(at 284.48 99.06 0)
			(effects
				(font
					(size 1.27 1.27)
				)
				(hide yes)
			)
		)
		(property "MPN" "LTC4412IS6#TRMPBF"
			(at 293.37 93.98 0)
			(effects
				(font
					(size 1.27 1.27)
					(thickness 0.15)
				)
			)
		)
		(property "Manufacturer" "Analog Devices"
			(at 316.23 114.3 0)
			(effects
				(font
					(size 1.27 1.27)
					(thickness 0.15)
				)
				(justify left bottom)
				(hide yes)
			)
		)
		(property "Author" "Antmicro"
			(at 316.23 116.84 0)
			(effects
				(font
					(size 1.27 1.27)
					(thickness 0.15)
				)
				(justify left bottom)
				(hide yes)
			)
		)
		(property "License" "Apache-2.0"
			(at 316.23 119.38 0)
			(effects
				(font
					(size 1.27 1.27)
					(thickness 0.15)
				)
				(justify left bottom)
				(hide yes)
			)
		)
		(pin "3"
		)
		(pin "5"
		)
		(pin "4"
		)
		(pin "2"
		)
		(pin "1"
		)
		(pin "6"
		)
		(instances
			(project "jetson-agx-thor-baseboard"
				(path ""
					(reference "U61")
					(unit 1)
				)
			)
		)
	)
	(symbol
		(lib_id "antmicroTransistorsFETsMOSFETsSingle:SISS05DN-T1-GE3")
		(at 251.46 57.15 90)
		(unit 1)
		(exclude_from_sim no)
		(in_bom yes)
		(on_board yes)
		(dnp no)
		(property "Reference" "Q33"
			(at 248.666 45.974 90)
			(effects
				(font
					(size 1.27 1.27)
					(thickness 0.15)
				)
			)
		)
		(property "Value" "SISS05DN-T1-GE3"
			(at 261.62 41.91 0)
			(effects
				(font
					(size 1.27 1.27)
					(thickness 0.15)
				)
				(justify left bottom)
				(hide yes)
			)
		)
		(property "Footprint" "antmicro-footprints:Vishay_PowerPAK_1212-8_Single"
			(at 264.16 41.91 0)
			(effects
				(font
					(size 1.27 1.27)
					(thickness 0.15)
				)
				(justify left bottom)
				(hide yes)
			)
		)
		(property "Datasheet" "https://www.vishay.com/docs/77029/siss05dn.pdf"
			(at 266.7 41.91 0)
			(effects
				(font
					(size 1.27 1.27)
					(thickness 0.15)
				)
				(justify left bottom)
				(hide yes)
			)
		)
		(property "Description" "Power MOSFET, P Channel, 30 V, 108 A, 0.0035 ohm, PowerPAK 1212, Surface Mount"
			(at 269.24 41.91 0)
			(effects
				(font
					(size 1.27 1.27)
					(thickness 0.15)
				)
				(justify left bottom)
				(hide yes)
			)
		)
		(property "MPN" "SISS05DN-T1-GE3"
			(at 249.174 47.752 90)
			(effects
				(font
					(size 1.27 1.27)
					(thickness 0.15)
				)
			)
		)
		(property "Manufacturer" "Vishay"
			(at 271.78 41.91 0)
			(effects
				(font
					(size 1.27 1.27)
					(thickness 0.15)
				)
				(justify left bottom)
				(hide yes)
			)
		)
		(property "Author" "Antmicro"
			(at 274.32 41.91 0)
			(effects
				(font
					(size 1.27 1.27)
					(thickness 0.15)
				)
				(justify left bottom)
				(hide yes)
			)
		)
		(property "License" "Apache-2.0"
			(at 276.86 41.91 0)
			(effects
				(font
					(size 1.27 1.27)
					(thickness 0.15)
				)
				(justify left bottom)
				(hide yes)
			)
		)
		(pin "1"
		)
		(pin "4"
		)
		(pin "3"
		)
		(pin "5"
		)
		(pin "2"
		)
		(instances
			(project "jetson-agx-thor-baseboard"
				(path ""
					(reference "Q33")
					(unit 1)
				)
			)
		)
	)
	(symbol
		(lib_id "antmicroTestPoints:TP_0.75mm_SMD")
		(at 317.5 200.66 0)
		(unit 1)
		(exclude_from_sim no)
		(in_bom no)
		(on_board yes)
		(dnp no)
		(property "Reference" "TP41"
			(at 321.818 200.66 0)
			(effects
				(font
					(size 1.27 1.27)
				)
				(justify left)
			)
		)
		(property "Value" "TP_0.75mm_SMD"
			(at 327.66 204.47 0)
			(effects
				(font
					(size 1.27 1.27)
					(thickness 0.15)
				)
				(justify left bottom)
				(hide yes)
			)
		)
		(property "Footprint" "antmicro-footprints:TP_SMD_0.75mm"
			(at 327.66 207.01 0)
			(effects
				(font
					(size 1.27 1.27)
					(thickness 0.15)
				)
				(justify left bottom)
				(hide yes)
			)
		)
		(property "Datasheet" ""
			(at 335.28 213.36 0)
			(effects
				(font
					(size 1.27 1.27)
					(thickness 0.15)
				)
				(justify left bottom)
				(hide yes)
			)
		)
		(property "Description" "SMT test point"
			(at 317.5 200.66 0)
			(effects
				(font
					(size 1.27 1.27)
				)
				(hide yes)
			)
		)
		(property "MPN" ""
			(at 328.295 212.09 0)
			(effects
				(font
					(size 1.27 1.27)
					(thickness 0.15)
				)
				(justify left bottom)
				(hide yes)
			)
		)
		(property "Manufacturer" ""
			(at 328.295 207.01 0)
			(effects
				(font
					(size 1.27 1.27)
					(thickness 0.15)
				)
				(justify left bottom)
				(hide yes)
			)
		)
		(property "Author" "Antmicro"
			(at 327.66 209.55 0)
			(effects
				(font
					(size 1.27 1.27)
					(thickness 0.15)
				)
				(justify left bottom)
				(hide yes)
			)
		)
		(property "License" "Apache-2.0"
			(at 327.66 212.09 0)
			(effects
				(font
					(size 1.27 1.27)
					(thickness 0.15)
				)
				(justify left bottom)
				(hide yes)
			)
		)
		(pin "1"
		)
		(instances
			(project "jetson-agx-thor-baseboard"
				(path ""
					(reference "TP41")
					(unit 1)
				)
			)
		)
	)
	(symbol
		(lib_id "antmicroResistors0402:R_470R_0402")
		(at 279.4 209.55 90)
		(unit 1)
		(exclude_from_sim no)
		(in_bom yes)
		(on_board yes)
		(dnp no)
		(fields_autoplaced yes)
		(property "Reference" "R35"
			(at 281.94 205.74 90)
			(effects
				(font
					(size 1.27 1.27)
					(thickness 0.15)
				)
				(justify right)
			)
		)
		(property "Value" "R_470R_0402"
			(at 292.1 189.23 0)
			(effects
				(font
					(size 1.27 1.27)
					(thickness 0.15)
				)
				(justify left bottom)
				(hide yes)
			)
		)
		(property "Footprint" "antmicro-footprints:R_0402_1005Metric"
			(at 294.64 189.23 0)
			(effects
				(font
					(size 1.27 1.27)
					(thickness 0.15)
				)
				(justify left bottom)
				(hide yes)
			)
		)
		(property "Datasheet" "https://www.bourns.com/docs/product-datasheets/cr.pdf"
			(at 297.18 189.23 0)
			(effects
				(font
					(size 1.27 1.27)
					(thickness 0.15)
				)
				(justify left bottom)
				(hide yes)
			)
		)
		(property "Description" "SMD Chip Resistor, 470 ohm, ± 1%, 62.5 mW, 0402 [1005 Metric], Thick Film, General Purpose"
			(at 279.4 209.55 0)
			(effects
				(font
					(size 1.27 1.27)
				)
				(hide yes)
			)
		)
		(property "MPN" "CR0402-FX-4700GLF"
			(at 299.72 189.23 0)
			(effects
				(font
					(size 1.27 1.27)
					(thickness 0.15)
				)
				(justify left bottom)
				(hide yes)
			)
		)
		(property "Manufacturer" "Bourns"
			(at 302.26 189.23 0)
			(effects
				(font
					(size 1.27 1.27)
					(thickness 0.15)
				)
				(justify left bottom)
				(hide yes)
			)
		)
		(property "License" "Apache-2.0"
			(at 304.8 189.23 0)
			(effects
				(font
					(size 1.27 1.27)
					(thickness 0.15)
				)
				(justify left bottom)
				(hide yes)
			)
		)
		(property "Author" "Antmicro"
			(at 307.34 189.23 0)
			(effects
				(font
					(size 1.27 1.27)
					(thickness 0.15)
				)
				(justify left bottom)
				(hide yes)
			)
		)
		(property "Val" "470R"
			(at 281.94 208.28 90)
			(effects
				(font
					(size 1.27 1.27)
					(thickness 0.15)
				)
				(justify right)
			)
		)
		(property "Tolerance" "1%"
			(at 289.56 189.23 0)
			(effects
				(font
					(size 1.27 1.27)
				)
				(justify left bottom)
				(hide yes)
			)
		)
		(pin "2"
		)
		(pin "1"
		)
		(instances
			(project "jetson-agx-thor-baseboard"
				(path ""
					(reference "R35")
					(unit 1)
				)
			)
		)
	)
	(symbol
		(lib_id "antmicroResistors0402:R_470R_0402")
		(at 259.08 209.55 90)
		(unit 1)
		(exclude_from_sim no)
		(in_bom yes)
		(on_board yes)
		(dnp no)
		(fields_autoplaced yes)
		(property "Reference" "R64"
			(at 261.62 205.74 90)
			(effects
				(font
					(size 1.27 1.27)
					(thickness 0.15)
				)
				(justify right)
			)
		)
		(property "Value" "R_470R_0402"
			(at 271.78 189.23 0)
			(effects
				(font
					(size 1.27 1.27)
					(thickness 0.15)
				)
				(justify left bottom)
				(hide yes)
			)
		)
		(property "Footprint" "antmicro-footprints:R_0402_1005Metric"
			(at 274.32 189.23 0)
			(effects
				(font
					(size 1.27 1.27)
					(thickness 0.15)
				)
				(justify left bottom)
				(hide yes)
			)
		)
		(property "Datasheet" "https://www.bourns.com/docs/product-datasheets/cr.pdf"
			(at 276.86 189.23 0)
			(effects
				(font
					(size 1.27 1.27)
					(thickness 0.15)
				)
				(justify left bottom)
				(hide yes)
			)
		)
		(property "Description" "SMD Chip Resistor, 470 ohm, ± 1%, 62.5 mW, 0402 [1005 Metric], Thick Film, General Purpose"
			(at 259.08 209.55 0)
			(effects
				(font
					(size 1.27 1.27)
				)
				(hide yes)
			)
		)
		(property "MPN" "CR0402-FX-4700GLF"
			(at 279.4 189.23 0)
			(effects
				(font
					(size 1.27 1.27)
					(thickness 0.15)
				)
				(justify left bottom)
				(hide yes)
			)
		)
		(property "Manufacturer" "Bourns"
			(at 281.94 189.23 0)
			(effects
				(font
					(size 1.27 1.27)
					(thickness 0.15)
				)
				(justify left bottom)
				(hide yes)
			)
		)
		(property "License" "Apache-2.0"
			(at 284.48 189.23 0)
			(effects
				(font
					(size 1.27 1.27)
					(thickness 0.15)
				)
				(justify left bottom)
				(hide yes)
			)
		)
		(property "Author" "Antmicro"
			(at 287.02 189.23 0)
			(effects
				(font
					(size 1.27 1.27)
					(thickness 0.15)
				)
				(justify left bottom)
				(hide yes)
			)
		)
		(property "Val" "470R"
			(at 261.62 208.28 90)
			(effects
				(font
					(size 1.27 1.27)
					(thickness 0.15)
				)
				(justify right)
			)
		)
		(property "Tolerance" "1%"
			(at 269.24 189.23 0)
			(effects
				(font
					(size 1.27 1.27)
				)
				(justify left bottom)
				(hide yes)
			)
		)
		(pin "2"
		)
		(pin "1"
		)
		(instances
			(project "jetson-agx-thor-baseboard"
				(path ""
					(reference "R64")
					(unit 1)
				)
			)
		)
	)
	(symbol
		(lib_id "antmicropower:GND")
		(at 308.61 144.78 0)
		(unit 1)
		(exclude_from_sim no)
		(in_bom yes)
		(on_board yes)
		(dnp no)
		(property "Reference" "#PWR0601"
			(at 308.61 151.13 0)
			(effects
				(font
					(size 1.27 1.27)
				)
				(justify left bottom)
				(hide yes)
			)
		)
		(property "Value" "GND"
			(at 308.61 148.59 0)
			(effects
				(font
					(size 1.27 1.27)
					(thickness 0.15)
				)
			)
		)
		(property "Footprint" ""
			(at 317.5 152.4 0)
			(effects
				(font
					(size 1.27 1.27)
					(thickness 0.15)
				)
				(justify left bottom)
				(hide yes)
			)
		)
		(property "Datasheet" ""
			(at 317.5 157.48 0)
			(effects
				(font
					(size 1.27 1.27)
					(thickness 0.15)
				)
				(justify left bottom)
				(hide yes)
			)
		)
		(property "Description" ""
			(at 308.61 144.78 0)
			(effects
				(font
					(size 1.27 1.27)
				)
				(hide yes)
			)
		)
		(property "Author" "Antmicro"
			(at 317.5 152.4 0)
			(effects
				(font
					(size 1.27 1.27)
					(thickness 0.15)
				)
				(justify left bottom)
				(hide yes)
			)
		)
		(property "License" "Apache-2.0"
			(at 317.5 154.94 0)
			(effects
				(font
					(size 1.27 1.27)
					(thickness 0.15)
				)
				(justify left bottom)
				(hide yes)
			)
		)
		(pin "1"
		)
		(instances
			(project "jetson-agx-thor-baseboard"
				(path ""
					(reference "#PWR0601")
					(unit 1)
				)
			)
		)
	)
	(symbol
		(lib_id "antmicroResistors0402:R_470R_0402")
		(at 269.24 209.55 90)
		(unit 1)
		(exclude_from_sim no)
		(in_bom yes)
		(on_board yes)
		(dnp no)
		(fields_autoplaced yes)
		(property "Reference" "R61"
			(at 271.78 205.74 90)
			(effects
				(font
					(size 1.27 1.27)
					(thickness 0.15)
				)
				(justify right)
			)
		)
		(property "Value" "R_470R_0402"
			(at 281.94 189.23 0)
			(effects
				(font
					(size 1.27 1.27)
					(thickness 0.15)
				)
				(justify left bottom)
				(hide yes)
			)
		)
		(property "Footprint" "antmicro-footprints:R_0402_1005Metric"
			(at 284.48 189.23 0)
			(effects
				(font
					(size 1.27 1.27)
					(thickness 0.15)
				)
				(justify left bottom)
				(hide yes)
			)
		)
		(property "Datasheet" "https://www.bourns.com/docs/product-datasheets/cr.pdf"
			(at 287.02 189.23 0)
			(effects
				(font
					(size 1.27 1.27)
					(thickness 0.15)
				)
				(justify left bottom)
				(hide yes)
			)
		)
		(property "Description" "SMD Chip Resistor, 470 ohm, ± 1%, 62.5 mW, 0402 [1005 Metric], Thick Film, General Purpose"
			(at 269.24 209.55 0)
			(effects
				(font
					(size 1.27 1.27)
				)
				(hide yes)
			)
		)
		(property "MPN" "CR0402-FX-4700GLF"
			(at 289.56 189.23 0)
			(effects
				(font
					(size 1.27 1.27)
					(thickness 0.15)
				)
				(justify left bottom)
				(hide yes)
			)
		)
		(property "Manufacturer" "Bourns"
			(at 292.1 189.23 0)
			(effects
				(font
					(size 1.27 1.27)
					(thickness 0.15)
				)
				(justify left bottom)
				(hide yes)
			)
		)
		(property "License" "Apache-2.0"
			(at 294.64 189.23 0)
			(effects
				(font
					(size 1.27 1.27)
					(thickness 0.15)
				)
				(justify left bottom)
				(hide yes)
			)
		)
		(property "Author" "Antmicro"
			(at 297.18 189.23 0)
			(effects
				(font
					(size 1.27 1.27)
					(thickness 0.15)
				)
				(justify left bottom)
				(hide yes)
			)
		)
		(property "Val" "470R"
			(at 271.78 208.28 90)
			(effects
				(font
					(size 1.27 1.27)
					(thickness 0.15)
				)
				(justify right)
			)
		)
		(property "Tolerance" "1%"
			(at 279.4 189.23 0)
			(effects
				(font
					(size 1.27 1.27)
				)
				(justify left bottom)
				(hide yes)
			)
		)
		(pin "2"
		)
		(pin "1"
		)
		(instances
			(project "jetson-agx-thor-baseboard"
				(path ""
					(reference "R61")
					(unit 1)
				)
			)
		)
	)
	(symbol
		(lib_id "antmicroTestPoints:TP_0.75mm_SMD")
		(at 317.5 185.42 0)
		(unit 1)
		(exclude_from_sim no)
		(in_bom no)
		(on_board yes)
		(dnp no)
		(property "Reference" "TP5"
			(at 321.818 185.42 0)
			(effects
				(font
					(size 1.27 1.27)
				)
				(justify left)
			)
		)
		(property "Value" "TP_0.75mm_SMD"
			(at 327.66 189.23 0)
			(effects
				(font
					(size 1.27 1.27)
					(thickness 0.15)
				)
				(justify left bottom)
				(hide yes)
			)
		)
		(property "Footprint" "antmicro-footprints:TP_SMD_0.75mm"
			(at 327.66 191.77 0)
			(effects
				(font
					(size 1.27 1.27)
					(thickness 0.15)
				)
				(justify left bottom)
				(hide yes)
			)
		)
		(property "Datasheet" ""
			(at 335.28 198.12 0)
			(effects
				(font
					(size 1.27 1.27)
					(thickness 0.15)
				)
				(justify left bottom)
				(hide yes)
			)
		)
		(property "Description" "SMT test point"
			(at 317.5 185.42 0)
			(effects
				(font
					(size 1.27 1.27)
				)
				(hide yes)
			)
		)
		(property "MPN" ""
			(at 328.295 196.85 0)
			(effects
				(font
					(size 1.27 1.27)
					(thickness 0.15)
				)
				(justify left bottom)
				(hide yes)
			)
		)
		(property "Manufacturer" ""
			(at 328.295 191.77 0)
			(effects
				(font
					(size 1.27 1.27)
					(thickness 0.15)
				)
				(justify left bottom)
				(hide yes)
			)
		)
		(property "Author" "Antmicro"
			(at 327.66 194.31 0)
			(effects
				(font
					(size 1.27 1.27)
					(thickness 0.15)
				)
				(justify left bottom)
				(hide yes)
			)
		)
		(property "License" "Apache-2.0"
			(at 327.66 196.85 0)
			(effects
				(font
					(size 1.27 1.27)
					(thickness 0.15)
				)
				(justify left bottom)
				(hide yes)
			)
		)
		(pin "1"
		)
		(instances
			(project "jetson-agx-thor-baseboard"
				(path ""
					(reference "TP5")
					(unit 1)
				)
			)
		)
	)
	(symbol
		(lib_id "antmicroLEDIndicationDiscrete:LED_G_0603_LTST-C190GKT")
		(at 248.92 215.9 90)
		(unit 1)
		(exclude_from_sim no)
		(in_bom yes)
		(on_board yes)
		(dnp no)
		(property "Reference" "D53"
			(at 250.19 212.09 90)
			(effects
				(font
					(size 1.27 1.27)
				)
				(justify right)
			)
		)
		(property "Value" "LED_G_0603_LTST-C190GKT"
			(at 256.54 193.04 0)
			(effects
				(font
					(size 1.27 1.27)
					(thickness 0.15)
				)
				(justify left bottom)
				(hide yes)
			)
		)
		(property "Footprint" "antmicro-footprints:LED_0603_1608Metric_G"
			(at 259.08 193.04 0)
			(effects
				(font
					(size 1.27 1.27)
					(thickness 0.15)
				)
				(justify left bottom)
				(hide yes)
			)
		)
		(property "Datasheet" "https://media.digikey.com/pdf/Data%20Sheets/Lite-On%20PDFs/LTST-C190GKT.pdf"
			(at 261.62 193.04 0)
			(effects
				(font
					(size 1.27 1.27)
					(thickness 0.15)
				)
				(justify left bottom)
				(hide yes)
			)
		)
		(property "Description" "LED, Green, SMD, 0603, 20 mA, 2.1 V, 569 nm"
			(at 248.92 215.9 0)
			(effects
				(font
					(size 1.27 1.27)
				)
				(hide yes)
			)
		)
		(property "MPN" "LTST-C190GKT"
			(at 264.16 193.04 0)
			(effects
				(font
					(size 1.27 1.27)
					(thickness 0.15)
				)
				(justify left bottom)
				(hide yes)
			)
		)
		(property "Manufacturer" "Lite-On"
			(at 266.7 193.04 0)
			(effects
				(font
					(size 1.27 1.27)
					(thickness 0.15)
				)
				(justify left bottom)
				(hide yes)
			)
		)
		(property "Author" "Antmicro"
			(at 269.24 193.04 0)
			(effects
				(font
					(size 1.27 1.27)
					(thickness 0.15)
				)
				(justify left bottom)
				(hide yes)
			)
		)
		(property "License" "Apache-2.0"
			(at 271.78 193.04 0)
			(effects
				(font
					(size 1.27 1.27)
					(thickness 0.15)
				)
				(justify left bottom)
				(hide yes)
			)
		)
		(property "Color" "Green"
			(at 250.19 214.63 90)
			(effects
				(font
					(size 1.27 1.27)
				)
				(justify right)
			)
		)
		(pin "1"
		)
		(pin "2"
		)
		(instances
			(project "jetson-agx-thor-baseboard"
				(path ""
					(reference "D53")
					(unit 1)
				)
			)
		)
	)
	(symbol
		(lib_id "antmicroLEDIndicationDiscrete:LED_G_0603_LTST-C190GKT")
		(at 228.6 215.9 90)
		(unit 1)
		(exclude_from_sim no)
		(in_bom yes)
		(on_board yes)
		(dnp no)
		(property "Reference" "D6"
			(at 229.87 212.09 90)
			(effects
				(font
					(size 1.27 1.27)
				)
				(justify right)
			)
		)
		(property "Value" "LED_G_0603_LTST-C190GKT"
			(at 236.22 193.04 0)
			(effects
				(font
					(size 1.27 1.27)
					(thickness 0.15)
				)
				(justify left bottom)
				(hide yes)
			)
		)
		(property "Footprint" "antmicro-footprints:LED_0603_1608Metric_G"
			(at 238.76 193.04 0)
			(effects
				(font
					(size 1.27 1.27)
					(thickness 0.15)
				)
				(justify left bottom)
				(hide yes)
			)
		)
		(property "Datasheet" "https://media.digikey.com/pdf/Data%20Sheets/Lite-On%20PDFs/LTST-C190GKT.pdf"
			(at 241.3 193.04 0)
			(effects
				(font
					(size 1.27 1.27)
					(thickness 0.15)
				)
				(justify left bottom)
				(hide yes)
			)
		)
		(property "Description" "LED, Green, SMD, 0603, 20 mA, 2.1 V, 569 nm"
			(at 228.6 215.9 0)
			(effects
				(font
					(size 1.27 1.27)
				)
				(hide yes)
			)
		)
		(property "MPN" "LTST-C190GKT"
			(at 243.84 193.04 0)
			(effects
				(font
					(size 1.27 1.27)
					(thickness 0.15)
				)
				(justify left bottom)
				(hide yes)
			)
		)
		(property "Manufacturer" "Lite-On"
			(at 246.38 193.04 0)
			(effects
				(font
					(size 1.27 1.27)
					(thickness 0.15)
				)
				(justify left bottom)
				(hide yes)
			)
		)
		(property "Author" "Antmicro"
			(at 248.92 193.04 0)
			(effects
				(font
					(size 1.27 1.27)
					(thickness 0.15)
				)
				(justify left bottom)
				(hide yes)
			)
		)
		(property "License" "Apache-2.0"
			(at 251.46 193.04 0)
			(effects
				(font
					(size 1.27 1.27)
					(thickness 0.15)
				)
				(justify left bottom)
				(hide yes)
			)
		)
		(property "Color" "Green"
			(at 229.87 214.63 90)
			(effects
				(font
					(size 1.27 1.27)
				)
				(justify right)
			)
		)
		(pin "1"
		)
		(pin "2"
		)
		(instances
			(project "jetson-agx-thor-baseboard"
				(path ""
					(reference "D6")
					(unit 1)
				)
			)
		)
	)
	(symbol
		(lib_id "antmicroResistors0402:R_200R_0402")
		(at 290.83 209.55 270)
		(mirror x)
		(unit 1)
		(exclude_from_sim no)
		(in_bom yes)
		(on_board yes)
		(dnp no)
		(property "Reference" "R79"
			(at 293.37 205.74 90)
			(effects
				(font
					(size 1.27 1.27)
				)
				(justify left)
			)
		)
		(property "Value" "R_200R_0402"
			(at 278.13 189.23 0)
			(effects
				(font
					(size 1.27 1.27)
					(thickness 0.15)
				)
				(justify left bottom)
				(hide yes)
			)
		)
		(property "Footprint" "antmicro-footprints:R_0402_1005Metric"
			(at 275.59 189.23 0)
			(effects
				(font
					(size 1.27 1.27)
					(thickness 0.15)
				)
				(justify left bottom)
				(hide yes)
			)
		)
		(property "Datasheet" "https://www.bourns.com/docs/product-datasheets/cr.pdf"
			(at 273.05 189.23 0)
			(effects
				(font
					(size 1.27 1.27)
					(thickness 0.15)
				)
				(justify left bottom)
				(hide yes)
			)
		)
		(property "Description" "SMD Chip Resistor, 200 ohm, ± 1%, 62.5 mW, 0402 [1005 Metric], Thick Film, General Purpose"
			(at 290.83 209.55 0)
			(effects
				(font
					(size 1.27 1.27)
				)
				(hide yes)
			)
		)
		(property "Manufacturer" "Bourns"
			(at 267.97 189.23 0)
			(effects
				(font
					(size 1.27 1.27)
					(thickness 0.15)
				)
				(justify left bottom)
				(hide yes)
			)
		)
		(property "MPN" "CR0402-FX-2000GLF"
			(at 270.51 189.23 0)
			(effects
				(font
					(size 1.27 1.27)
					(thickness 0.15)
				)
				(justify left bottom)
				(hide yes)
			)
		)
		(property "Val" "200R"
			(at 293.37 208.28 90)
			(effects
				(font
					(size 1.27 1.27)
					(thickness 0.15)
				)
				(justify left)
			)
		)
		(property "License" "Apache-2.0"
			(at 265.43 189.23 0)
			(effects
				(font
					(size 1.27 1.27)
					(thickness 0.15)
				)
				(justify left bottom)
				(hide yes)
			)
		)
		(property "Author" "Antmicro"
			(at 262.89 189.23 0)
			(effects
				(font
					(size 1.27 1.27)
					(thickness 0.15)
				)
				(justify left bottom)
				(hide yes)
			)
		)
		(property "Tolerance" "1%"
			(at 280.67 189.23 0)
			(effects
				(font
					(size 1.27 1.27)
				)
				(justify left bottom)
				(hide yes)
			)
		)
		(pin "1"
		)
		(pin "2"
		)
		(instances
			(project "jetson-agx-thor-baseboard"
				(path ""
					(reference "R79")
					(unit 1)
				)
			)
		)
	)
	(symbol
		(lib_id "antmicropower:+3V3_AON")
		(at 300.99 181.61 0)
		(unit 1)
		(exclude_from_sim no)
		(in_bom yes)
		(on_board yes)
		(dnp no)
		(property "Reference" "#PWR061"
			(at 300.99 185.42 0)
			(effects
				(font
					(size 1.27 1.27)
				)
				(hide yes)
			)
		)
		(property "Value" "+3V3_AON"
			(at 300.99 177.8 0)
			(effects
				(font
					(size 1.27 1.27)
				)
			)
		)
		(property "Footprint" ""
			(at 300.99 181.61 0)
			(effects
				(font
					(size 1.27 1.27)
				)
				(hide yes)
			)
		)
		(property "Datasheet" ""
			(at 300.99 181.61 0)
			(effects
				(font
					(size 1.27 1.27)
				)
				(hide yes)
			)
		)
		(property "Description" ""
			(at 300.99 181.61 0)
			(effects
				(font
					(size 1.27 1.27)
				)
				(hide yes)
			)
		)
		(pin "1"
		)
		(instances
			(project "jetson-agx-thor-baseboard"
				(path ""
					(reference "#PWR061")
					(unit 1)
				)
			)
		)
	)
	(symbol
		(lib_id "antmicropower:GND")
		(at 280.67 48.26 0)
		(unit 1)
		(exclude_from_sim no)
		(in_bom yes)
		(on_board yes)
		(dnp no)
		(property "Reference" "#PWR0635"
			(at 289.56 50.8 0)
			(effects
				(font
					(size 1.27 1.27)
					(thickness 0.15)
				)
				(justify left bottom)
				(hide yes)
			)
		)
		(property "Value" "GND"
			(at 280.67 52.07 0)
			(effects
				(font
					(size 1.27 1.27)
					(thickness 0.15)
				)
			)
		)
		(property "Footprint" ""
			(at 289.56 55.88 0)
			(effects
				(font
					(size 1.27 1.27)
					(thickness 0.15)
				)
				(justify left bottom)
				(hide yes)
			)
		)
		(property "Datasheet" ""
			(at 289.56 60.96 0)
			(effects
				(font
					(size 1.27 1.27)
					(thickness 0.15)
				)
				(justify left bottom)
				(hide yes)
			)
		)
		(property "Description" ""
			(at 289.56 63.5 0)
			(effects
				(font
					(size 1.27 1.27)
				)
				(justify left bottom)
				(hide yes)
			)
		)
		(property "Author" "Antmicro"
			(at 289.56 55.88 0)
			(effects
				(font
					(size 1.27 1.27)
					(thickness 0.15)
				)
				(justify left bottom)
				(hide yes)
			)
		)
		(property "License" "Apache-2.0"
			(at 289.56 58.42 0)
			(effects
				(font
					(size 1.27 1.27)
					(thickness 0.15)
				)
				(justify left bottom)
				(hide yes)
			)
		)
		(pin "1"
		)
		(instances
			(project ""
				(path ""
					(reference "#PWR0635")
					(unit 1)
				)
			)
		)
	)
	(symbol
		(lib_id "antmicroCapacitors0402:C_1u_25V_0402")
		(at 308.61 107.95 90)
		(unit 1)
		(exclude_from_sim no)
		(in_bom no)
		(on_board yes)
		(dnp yes)
		(fields_autoplaced yes)
		(property "Reference" "C261"
			(at 311.15 104.1336 90)
			(effects
				(font
					(size 1.27 1.27)
					(thickness 0.15)
				)
				(justify right)
			)
		)
		(property "Value" "C_1u_25V_0402"
			(at 318.77 87.63 0)
			(effects
				(font
					(size 1.27 1.27)
					(thickness 0.15)
				)
				(justify left bottom)
				(hide yes)
			)
		)
		(property "Footprint" "antmicro-footprints:C_0402_1005Metric"
			(at 321.31 87.63 0)
			(effects
				(font
					(size 1.27 1.27)
					(thickness 0.15)
				)
				(justify left bottom)
				(hide yes)
			)
		)
		(property "Datasheet" "https://www.murata.com/products/productdetail?partno=GRM155R61E105KE11%23"
			(at 323.85 87.63 0)
			(effects
				(font
					(size 1.27 1.27)
					(thickness 0.15)
				)
				(justify left bottom)
				(hide yes)
			)
		)
		(property "Description" "SMD Multilayer Ceramic Capacitor, 1 µF, 25 V, 0402 [1005 Metric], ± 10%, X5R, GRM Series"
			(at 308.61 107.95 0)
			(effects
				(font
					(size 1.27 1.27)
				)
				(hide yes)
			)
		)
		(property "MPN" "GRM155R61E105KE11J"
			(at 326.39 87.63 0)
			(effects
				(font
					(size 1.27 1.27)
					(thickness 0.15)
				)
				(justify left bottom)
				(hide yes)
			)
		)
		(property "Manufacturer" "Murata"
			(at 328.93 87.63 0)
			(effects
				(font
					(size 1.27 1.27)
					(thickness 0.15)
				)
				(justify left bottom)
				(hide yes)
			)
		)
		(property "License" "Apache-2.0"
			(at 331.47 87.63 0)
			(effects
				(font
					(size 1.27 1.27)
					(thickness 0.15)
				)
				(justify left bottom)
				(hide yes)
			)
		)
		(property "Author" "Antmicro"
			(at 334.01 87.63 0)
			(effects
				(font
					(size 1.27 1.27)
					(thickness 0.15)
				)
				(justify left bottom)
				(hide yes)
			)
		)
		(property "Val" "1u"
			(at 311.15 106.6736 90)
			(effects
				(font
					(size 1.27 1.27)
					(thickness 0.15)
				)
				(justify right)
			)
		)
		(property "Voltage" "25V"
			(at 336.55 87.63 0)
			(effects
				(font
					(size 1.27 1.27)
				)
				(justify left bottom)
				(hide yes)
			)
		)
		(property "Dielectric" "X5R"
			(at 339.09 87.63 0)
			(effects
				(font
					(size 1.27 1.27)
				)
				(justify left bottom)
				(hide yes)
			)
		)
		(pin "1"
		)
		(pin "2"
		)
		(instances
			(project "jetson-agx-thor-baseboard"
				(path ""
					(reference "C261")
					(unit 1)
				)
			)
		)
	)
	(symbol
		(lib_id "antmicropower:GND")
		(at 281.94 107.95 0)
		(unit 1)
		(exclude_from_sim no)
		(in_bom yes)
		(on_board yes)
		(dnp no)
		(property "Reference" "#PWR0598"
			(at 281.94 114.3 0)
			(effects
				(font
					(size 1.27 1.27)
				)
				(justify left bottom)
				(hide yes)
			)
		)
		(property "Value" "GND"
			(at 281.94 111.76 0)
			(effects
				(font
					(size 1.27 1.27)
					(thickness 0.15)
				)
			)
		)
		(property "Footprint" ""
			(at 290.83 115.57 0)
			(effects
				(font
					(size 1.27 1.27)
					(thickness 0.15)
				)
				(justify left bottom)
				(hide yes)
			)
		)
		(property "Datasheet" ""
			(at 290.83 120.65 0)
			(effects
				(font
					(size 1.27 1.27)
					(thickness 0.15)
				)
				(justify left bottom)
				(hide yes)
			)
		)
		(property "Description" ""
			(at 281.94 107.95 0)
			(effects
				(font
					(size 1.27 1.27)
				)
				(hide yes)
			)
		)
		(property "Author" "Antmicro"
			(at 290.83 115.57 0)
			(effects
				(font
					(size 1.27 1.27)
					(thickness 0.15)
				)
				(justify left bottom)
				(hide yes)
			)
		)
		(property "License" "Apache-2.0"
			(at 290.83 118.11 0)
			(effects
				(font
					(size 1.27 1.27)
					(thickness 0.15)
				)
				(justify left bottom)
				(hide yes)
			)
		)
		(pin "1"
		)
		(instances
			(project "jetson-agx-thor-baseboard"
				(path ""
					(reference "#PWR0598")
					(unit 1)
				)
			)
		)
	)
	(symbol
		(lib_id "antmicroCapacitors0402:C_10u_0402")
		(at 110.49 87.63 90)
		(unit 1)
		(exclude_from_sim no)
		(in_bom yes)
		(on_board yes)
		(dnp no)
		(property "Reference" "C75"
			(at 112.395 83.82 90)
			(effects
				(font
					(size 1.27 1.27)
					(thickness 0.15)
				)
				(justify right)
			)
		)
		(property "Value" "C_10u_0402"
			(at 120.65 67.31 0)
			(effects
				(font
					(size 1.27 1.27)
					(thickness 0.15)
				)
				(justify left bottom)
				(hide yes)
			)
		)
		(property "Footprint" "antmicro-footprints:C_0402_1005Metric"
			(at 123.19 67.31 0)
			(effects
				(font
					(size 1.27 1.27)
					(thickness 0.15)
				)
				(justify left bottom)
				(hide yes)
			)
		)
		(property "Datasheet" "https://www.yageo.com/en/Chart/Download/pdf/CC0402MRX5R5BB106"
			(at 125.73 67.31 0)
			(effects
				(font
					(size 1.27 1.27)
					(thickness 0.15)
				)
				(justify left bottom)
				(hide yes)
			)
		)
		(property "Description" "SMD Multilayer Ceramic Capacitor, 10 µF, 6.3 V, 0402 [1005 Metric], ± 20%, X5R, CC Series"
			(at 110.49 87.63 0)
			(effects
				(font
					(size 1.27 1.27)
				)
				(hide yes)
			)
		)
		(property "MPN" "CC0402MRX5R5BB106"
			(at 128.27 67.31 0)
			(effects
				(font
					(size 1.27 1.27)
					(thickness 0.15)
				)
				(justify left bottom)
				(hide yes)
			)
		)
		(property "Manufacturer" "YAGEO"
			(at 130.81 67.31 0)
			(effects
				(font
					(size 1.27 1.27)
					(thickness 0.15)
				)
				(justify left bottom)
				(hide yes)
			)
		)
		(property "License" "Apache-2.0"
			(at 133.35 67.31 0)
			(effects
				(font
					(size 1.27 1.27)
					(thickness 0.15)
				)
				(justify left bottom)
				(hide yes)
			)
		)
		(property "Author" "Antmicro"
			(at 135.89 67.31 0)
			(effects
				(font
					(size 1.27 1.27)
					(thickness 0.15)
				)
				(justify left bottom)
				(hide yes)
			)
		)
		(property "Val" "10u"
			(at 112.395 86.36 90)
			(effects
				(font
					(size 1.27 1.27)
					(thickness 0.15)
				)
				(justify right)
			)
		)
		(property "Voltage" ""
			(at 138.43 67.31 0)
			(effects
				(font
					(size 1.27 1.27)
				)
				(justify left bottom)
				(hide yes)
			)
		)
		(property "Dielectric" ""
			(at 140.97 67.31 0)
			(effects
				(font
					(size 1.27 1.27)
				)
				(justify left bottom)
				(hide yes)
			)
		)
		(pin "1"
		)
		(pin "2"
		)
		(instances
			(project "jetson-agx-thor-baseboard"
				(path ""
					(reference "C75")
					(unit 1)
				)
			)
		)
	)
	(symbol
		(lib_id "antmicroTransistorsFETsMOSFETsSingle:SISS05DN-T1-GE3")
		(at 303.53 91.44 90)
		(unit 1)
		(exclude_from_sim no)
		(in_bom no)
		(on_board yes)
		(dnp yes)
		(fields_autoplaced yes)
		(property "Reference" "Q5"
			(at 300.99 78.74 90)
			(effects
				(font
					(size 1.27 1.27)
					(thickness 0.15)
				)
			)
		)
		(property "Value" "SISS05DN-T1-GE3"
			(at 313.69 76.2 0)
			(effects
				(font
					(size 1.27 1.27)
					(thickness 0.15)
				)
				(justify left bottom)
				(hide yes)
			)
		)
		(property "Footprint" "antmicro-footprints:Vishay_PowerPAK_1212-8_Single"
			(at 316.23 76.2 0)
			(effects
				(font
					(size 1.27 1.27)
					(thickness 0.15)
				)
				(justify left bottom)
				(hide yes)
			)
		)
		(property "Datasheet" "https://www.vishay.com/docs/77029/siss05dn.pdf"
			(at 318.77 76.2 0)
			(effects
				(font
					(size 1.27 1.27)
					(thickness 0.15)
				)
				(justify left bottom)
				(hide yes)
			)
		)
		(property "Description" "Power MOSFET, P Channel, 30 V, 108 A, 0.0035 ohm, PowerPAK 1212, Surface Mount"
			(at 321.31 76.2 0)
			(effects
				(font
					(size 1.27 1.27)
					(thickness 0.15)
				)
				(justify left bottom)
				(hide yes)
			)
		)
		(property "MPN" "SISS05DN-T1-GE3"
			(at 300.99 81.28 90)
			(effects
				(font
					(size 1.27 1.27)
					(thickness 0.15)
				)
			)
		)
		(property "Manufacturer" "Vishay"
			(at 323.85 76.2 0)
			(effects
				(font
					(size 1.27 1.27)
					(thickness 0.15)
				)
				(justify left bottom)
				(hide yes)
			)
		)
		(property "Author" "Antmicro"
			(at 326.39 76.2 0)
			(effects
				(font
					(size 1.27 1.27)
					(thickness 0.15)
				)
				(justify left bottom)
				(hide yes)
			)
		)
		(property "License" "Apache-2.0"
			(at 328.93 76.2 0)
			(effects
				(font
					(size 1.27 1.27)
					(thickness 0.15)
				)
				(justify left bottom)
				(hide yes)
			)
		)
		(pin "1"
		)
		(pin "4"
		)
		(pin "3"
		)
		(pin "5"
		)
		(pin "2"
		)
		(instances
			(project "jetson-agx-thor-baseboard"
				(path ""
					(reference "Q5")
					(unit 1)
				)
			)
		)
	)
	(symbol
		(lib_id "antmicropower:GND")
		(at 219.71 43.18 0)
		(unit 1)
		(exclude_from_sim no)
		(in_bom yes)
		(on_board yes)
		(dnp no)
		(property "Reference" "#PWR044"
			(at 219.71 49.53 0)
			(effects
				(font
					(size 1.27 1.27)
				)
				(justify left bottom)
				(hide yes)
			)
		)
		(property "Value" "GND"
			(at 219.71 46.99 0)
			(effects
				(font
					(size 1.27 1.27)
					(thickness 0.15)
				)
			)
		)
		(property "Footprint" ""
			(at 228.6 50.8 0)
			(effects
				(font
					(size 1.27 1.27)
					(thickness 0.15)
				)
				(justify left bottom)
				(hide yes)
			)
		)
		(property "Datasheet" ""
			(at 228.6 55.88 0)
			(effects
				(font
					(size 1.27 1.27)
					(thickness 0.15)
				)
				(justify left bottom)
				(hide yes)
			)
		)
		(property "Description" ""
			(at 219.71 43.18 0)
			(effects
				(font
					(size 1.27 1.27)
				)
				(hide yes)
			)
		)
		(property "Author" "Antmicro"
			(at 228.6 50.8 0)
			(effects
				(font
					(size 1.27 1.27)
					(thickness 0.15)
				)
				(justify left bottom)
				(hide yes)
			)
		)
		(property "License" "Apache-2.0"
			(at 228.6 53.34 0)
			(effects
				(font
					(size 1.27 1.27)
					(thickness 0.15)
				)
				(justify left bottom)
				(hide yes)
			)
		)
		(pin "1"
		)
		(instances
			(project "jetson-agx-thor-baseboard"
				(path ""
					(reference "#PWR044")
					(unit 1)
				)
			)
		)
	)
	(symbol
		(lib_id "antmicroResistors0402:R_10k_0402")
		(at 101.6 95.25 270)
		(mirror x)
		(unit 1)
		(exclude_from_sim no)
		(in_bom yes)
		(on_board yes)
		(dnp no)
		(property "Reference" "R417"
			(at 99.06 91.44 90)
			(effects
				(font
					(size 1.27 1.27)
					(thickness 0.15)
				)
				(justify right)
			)
		)
		(property "Value" "R_10k_0402"
			(at 88.9 74.93 0)
			(effects
				(font
					(size 1.27 1.27)
					(thickness 0.15)
				)
				(justify left bottom)
				(hide yes)
			)
		)
		(property "Footprint" "antmicro-footprints:R_0402_1005Metric"
			(at 86.36 74.93 0)
			(effects
				(font
					(size 1.27 1.27)
					(thickness 0.15)
				)
				(justify left bottom)
				(hide yes)
			)
		)
		(property "Datasheet" "https://www.bourns.com/docs/product-datasheets/cr.pdf"
			(at 83.82 74.93 0)
			(effects
				(font
					(size 1.27 1.27)
					(thickness 0.15)
				)
				(justify left bottom)
				(hide yes)
			)
		)
		(property "Description" "SMD Chip Resistor, 10 kohm, ± 1%, 62.5 mW, 0402 [1005 Metric], Thick Film, General Purpose"
			(at 71.12 74.93 0)
			(effects
				(font
					(size 1.27 1.27)
				)
				(justify left bottom)
				(hide yes)
			)
		)
		(property "MPN" "CR0402-FX-1002GLF"
			(at 81.28 74.93 0)
			(effects
				(font
					(size 1.27 1.27)
					(thickness 0.15)
				)
				(justify left bottom)
				(hide yes)
			)
		)
		(property "Manufacturer" "Bourns"
			(at 78.74 74.93 0)
			(effects
				(font
					(size 1.27 1.27)
					(thickness 0.15)
				)
				(justify left bottom)
				(hide yes)
			)
		)
		(property "License" "Apache-2.0"
			(at 76.2 74.93 0)
			(effects
				(font
					(size 1.27 1.27)
					(thickness 0.15)
				)
				(justify left bottom)
				(hide yes)
			)
		)
		(property "Author" "Antmicro"
			(at 73.66 74.93 0)
			(effects
				(font
					(size 1.27 1.27)
					(thickness 0.15)
				)
				(justify left bottom)
				(hide yes)
			)
		)
		(property "Val" "10k"
			(at 99.06 93.98 90)
			(effects
				(font
					(size 1.27 1.27)
					(thickness 0.15)
				)
				(justify right)
			)
		)
		(property "Tolerance" "1%"
			(at 91.44 74.93 0)
			(effects
				(font
					(size 1.27 1.27)
				)
				(justify left bottom)
				(hide yes)
			)
		)
		(pin "1"
		)
		(pin "2"
		)
		(instances
			(project "jetson-agx-thor-baseboard"
				(path ""
					(reference "R417")
					(unit 1)
				)
			)
		)
	)
	(symbol
		(lib_id "antmicropower:PWR_FLAG")
		(at 214.63 34.29 0)
		(unit 1)
		(exclude_from_sim no)
		(in_bom yes)
		(on_board yes)
		(dnp no)
		(property "Reference" "#FLG01"
			(at 214.63 32.385 0)
			(effects
				(font
					(size 1.27 1.27)
				)
				(hide yes)
			)
		)
		(property "Value" "PWR_FLAG"
			(at 213.36 30.48 0)
			(effects
				(font
					(size 1.27 1.27)
				)
			)
		)
		(property "Footprint" ""
			(at 214.63 34.29 0)
			(effects
				(font
					(size 1.27 1.27)
				)
				(hide yes)
			)
		)
		(property "Datasheet" ""
			(at 214.63 34.29 0)
			(effects
				(font
					(size 1.27 1.27)
				)
				(hide yes)
			)
		)
		(property "Description" ""
			(at 214.63 34.29 0)
			(effects
				(font
					(size 1.27 1.27)
				)
				(hide yes)
			)
		)
		(pin "1"
		)
		(instances
			(project "jetson-agx-thor-baseboard"
				(path ""
					(reference "#FLG01")
					(unit 1)
				)
			)
		)
	)
	(symbol
		(lib_id "antmicropower:VCC")
		(at 322.58 35.56 0)
		(unit 1)
		(exclude_from_sim no)
		(in_bom yes)
		(on_board yes)
		(dnp no)
		(property "Reference" "#PWR0573"
			(at 322.58 39.37 0)
			(effects
				(font
					(size 1.27 1.27)
				)
				(justify left bottom)
				(hide yes)
			)
		)
		(property "Value" "VCC"
			(at 320.675 31.75 0)
			(effects
				(font
					(size 1.27 1.27)
				)
				(justify left)
			)
		)
		(property "Footprint" ""
			(at 322.58 35.56 0)
			(effects
				(font
					(size 1.27 1.27)
				)
				(hide yes)
			)
		)
		(property "Datasheet" ""
			(at 322.58 35.56 0)
			(effects
				(font
					(size 1.27 1.27)
				)
				(hide yes)
			)
		)
		(property "Description" ""
			(at 322.58 35.56 0)
			(effects
				(font
					(size 1.27 1.27)
				)
				(hide yes)
			)
		)
		(pin "1"
		)
		(instances
			(project "jetson-agx-thor-baseboard"
				(path ""
					(reference "#PWR0573")
					(unit 1)
				)
			)
		)
	)
	(symbol
		(lib_id "antmicroResistors0402:R_200R_0402")
		(at 300.99 209.55 270)
		(mirror x)
		(unit 1)
		(exclude_from_sim no)
		(in_bom yes)
		(on_board yes)
		(dnp no)
		(property "Reference" "R32"
			(at 303.53 205.74 90)
			(effects
				(font
					(size 1.27 1.27)
				)
				(justify left)
			)
		)
		(property "Value" "R_200R_0402"
			(at 288.29 189.23 0)
			(effects
				(font
					(size 1.27 1.27)
					(thickness 0.15)
				)
				(justify left bottom)
				(hide yes)
			)
		)
		(property "Footprint" "antmicro-footprints:R_0402_1005Metric"
			(at 285.75 189.23 0)
			(effects
				(font
					(size 1.27 1.27)
					(thickness 0.15)
				)
				(justify left bottom)
				(hide yes)
			)
		)
		(property "Datasheet" "https://www.bourns.com/docs/product-datasheets/cr.pdf"
			(at 283.21 189.23 0)
			(effects
				(font
					(size 1.27 1.27)
					(thickness 0.15)
				)
				(justify left bottom)
				(hide yes)
			)
		)
		(property "Description" "SMD Chip Resistor, 200 ohm, ± 1%, 62.5 mW, 0402 [1005 Metric], Thick Film, General Purpose"
			(at 300.99 209.55 0)
			(effects
				(font
					(size 1.27 1.27)
				)
				(hide yes)
			)
		)
		(property "Manufacturer" "Bourns"
			(at 278.13 189.23 0)
			(effects
				(font
					(size 1.27 1.27)
					(thickness 0.15)
				)
				(justify left bottom)
				(hide yes)
			)
		)
		(property "MPN" "CR0402-FX-2000GLF"
			(at 280.67 189.23 0)
			(effects
				(font
					(size 1.27 1.27)
					(thickness 0.15)
				)
				(justify left bottom)
				(hide yes)
			)
		)
		(property "Val" "200R"
			(at 303.53 208.28 90)
			(effects
				(font
					(size 1.27 1.27)
					(thickness 0.15)
				)
				(justify left)
			)
		)
		(property "License" "Apache-2.0"
			(at 275.59 189.23 0)
			(effects
				(font
					(size 1.27 1.27)
					(thickness 0.15)
				)
				(justify left bottom)
				(hide yes)
			)
		)
		(property "Author" "Antmicro"
			(at 273.05 189.23 0)
			(effects
				(font
					(size 1.27 1.27)
					(thickness 0.15)
				)
				(justify left bottom)
				(hide yes)
			)
		)
		(property "Tolerance" "1%"
			(at 290.83 189.23 0)
			(effects
				(font
					(size 1.27 1.27)
				)
				(justify left bottom)
				(hide yes)
			)
		)
		(pin "1"
		)
		(pin "2"
		)
		(instances
			(project "jetson-agx-thor-baseboard"
				(path ""
					(reference "R32")
					(unit 1)
				)
			)
		)
	)
	(symbol
		(lib_id "antmicroResistors0402:R_470R_0402")
		(at 377.19 195.58 90)
		(unit 1)
		(exclude_from_sim no)
		(in_bom yes)
		(on_board yes)
		(dnp no)
		(fields_autoplaced yes)
		(property "Reference" "R240"
			(at 379.73 191.77 90)
			(effects
				(font
					(size 1.27 1.27)
					(thickness 0.15)
				)
				(justify right)
			)
		)
		(property "Value" "R_470R_0402"
			(at 389.89 175.26 0)
			(effects
				(font
					(size 1.27 1.27)
					(thickness 0.15)
				)
				(justify left bottom)
				(hide yes)
			)
		)
		(property "Footprint" "antmicro-footprints:R_0402_1005Metric"
			(at 392.43 175.26 0)
			(effects
				(font
					(size 1.27 1.27)
					(thickness 0.15)
				)
				(justify left bottom)
				(hide yes)
			)
		)
		(property "Datasheet" "https://www.bourns.com/docs/product-datasheets/cr.pdf"
			(at 394.97 175.26 0)
			(effects
				(font
					(size 1.27 1.27)
					(thickness 0.15)
				)
				(justify left bottom)
				(hide yes)
			)
		)
		(property "Description" "SMD Chip Resistor, 470 ohm, ± 1%, 62.5 mW, 0402 [1005 Metric], Thick Film, General Purpose"
			(at 377.19 195.58 0)
			(effects
				(font
					(size 1.27 1.27)
				)
				(hide yes)
			)
		)
		(property "MPN" "CR0402-FX-4700GLF"
			(at 397.51 175.26 0)
			(effects
				(font
					(size 1.27 1.27)
					(thickness 0.15)
				)
				(justify left bottom)
				(hide yes)
			)
		)
		(property "Manufacturer" "Bourns"
			(at 400.05 175.26 0)
			(effects
				(font
					(size 1.27 1.27)
					(thickness 0.15)
				)
				(justify left bottom)
				(hide yes)
			)
		)
		(property "License" "Apache-2.0"
			(at 402.59 175.26 0)
			(effects
				(font
					(size 1.27 1.27)
					(thickness 0.15)
				)
				(justify left bottom)
				(hide yes)
			)
		)
		(property "Author" "Antmicro"
			(at 405.13 175.26 0)
			(effects
				(font
					(size 1.27 1.27)
					(thickness 0.15)
				)
				(justify left bottom)
				(hide yes)
			)
		)
		(property "Val" "470R"
			(at 379.73 194.31 90)
			(effects
				(font
					(size 1.27 1.27)
					(thickness 0.15)
				)
				(justify right)
			)
		)
		(property "Tolerance" "1%"
			(at 387.35 175.26 0)
			(effects
				(font
					(size 1.27 1.27)
				)
				(justify left bottom)
				(hide yes)
			)
		)
		(pin "2"
		)
		(pin "1"
		)
		(instances
			(project "jetson-agx-thor-baseboard"
				(path ""
					(reference "R240")
					(unit 1)
				)
			)
		)
	)
	(symbol
		(lib_id "antmicropower:GND")
		(at 259.08 217.17 0)
		(unit 1)
		(exclude_from_sim no)
		(in_bom yes)
		(on_board yes)
		(dnp no)
		(property "Reference" "#PWR0189"
			(at 259.08 223.52 0)
			(effects
				(font
					(size 1.27 1.27)
				)
				(justify left bottom)
				(hide yes)
			)
		)
		(property "Value" "GND"
			(at 259.08 220.98 0)
			(effects
				(font
					(size 1.27 1.27)
					(thickness 0.15)
				)
			)
		)
		(property "Footprint" ""
			(at 267.97 224.79 0)
			(effects
				(font
					(size 1.27 1.27)
					(thickness 0.15)
				)
				(justify left bottom)
				(hide yes)
			)
		)
		(property "Datasheet" ""
			(at 267.97 229.87 0)
			(effects
				(font
					(size 1.27 1.27)
					(thickness 0.15)
				)
				(justify left bottom)
				(hide yes)
			)
		)
		(property "Description" ""
			(at 259.08 217.17 0)
			(effects
				(font
					(size 1.27 1.27)
				)
				(hide yes)
			)
		)
		(property "Author" "Antmicro"
			(at 267.97 224.79 0)
			(effects
				(font
					(size 1.27 1.27)
					(thickness 0.15)
				)
				(justify left bottom)
				(hide yes)
			)
		)
		(property "License" "Apache-2.0"
			(at 267.97 227.33 0)
			(effects
				(font
					(size 1.27 1.27)
					(thickness 0.15)
				)
				(justify left bottom)
				(hide yes)
			)
		)
		(pin "1"
		)
		(instances
			(project "jetson-agx-thor-baseboard"
				(path ""
					(reference "#PWR0189")
					(unit 1)
				)
			)
		)
	)
	(symbol
		(lib_id "antmicropower:VCC")
		(at 224.79 34.29 0)
		(unit 1)
		(exclude_from_sim no)
		(in_bom yes)
		(on_board yes)
		(dnp no)
		(property "Reference" "#PWR0522"
			(at 224.79 38.1 0)
			(effects
				(font
					(size 1.27 1.27)
				)
				(justify left bottom)
				(hide yes)
			)
		)
		(property "Value" "VCC_IN"
			(at 222.885 30.48 0)
			(effects
				(font
					(size 1.27 1.27)
				)
				(justify left)
			)
		)
		(property "Footprint" ""
			(at 224.79 34.29 0)
			(effects
				(font
					(size 1.27 1.27)
				)
				(hide yes)
			)
		)
		(property "Datasheet" ""
			(at 224.79 34.29 0)
			(effects
				(font
					(size 1.27 1.27)
				)
				(hide yes)
			)
		)
		(property "Description" ""
			(at 224.79 34.29 0)
			(effects
				(font
					(size 1.27 1.27)
				)
				(hide yes)
			)
		)
		(pin "1"
		)
		(instances
			(project "jetson-agx-thor-baseboard"
				(path ""
					(reference "#PWR0522")
					(unit 1)
				)
			)
		)
	)
	(symbol
		(lib_id "antmicropower:+3V3")
		(at 290.83 181.61 0)
		(unit 1)
		(exclude_from_sim no)
		(in_bom yes)
		(on_board yes)
		(dnp no)
		(property "Reference" "#PWR0510"
			(at 306.07 181.61 0)
			(effects
				(font
					(size 1.27 1.27)
					(thickness 0.15)
				)
				(justify left bottom)
				(hide yes)
			)
		)
		(property "Value" "+3V3"
			(at 290.068 177.8 0)
			(effects
				(font
					(size 1.27 1.27)
					(thickness 0.15)
				)
			)
		)
		(property "Footprint" ""
			(at 306.07 189.23 0)
			(effects
				(font
					(size 1.27 1.27)
					(thickness 0.15)
				)
				(justify left bottom)
				(hide yes)
			)
		)
		(property "Datasheet" ""
			(at 306.07 191.77 0)
			(effects
				(font
					(size 1.27 1.27)
					(thickness 0.15)
				)
				(justify left bottom)
				(hide yes)
			)
		)
		(property "Description" ""
			(at 290.83 181.61 0)
			(effects
				(font
					(size 1.27 1.27)
				)
				(hide yes)
			)
		)
		(property "Author" "Antmicro"
			(at 306.07 184.15 0)
			(effects
				(font
					(size 1.27 1.27)
					(thickness 0.15)
				)
				(justify left bottom)
				(hide yes)
			)
		)
		(property "License" "Apache-2.0"
			(at 306.07 186.69 0)
			(effects
				(font
					(size 1.27 1.27)
					(thickness 0.15)
				)
				(justify left bottom)
				(hide yes)
			)
		)
		(pin "1"
		)
		(instances
			(project "jetson-agx-thor-baseboard"
				(path ""
					(reference "#PWR0510")
					(unit 1)
				)
			)
		)
	)
	(symbol
		(lib_id "antmicropower:VCC")
		(at 238.76 181.61 0)
		(unit 1)
		(exclude_from_sim no)
		(in_bom yes)
		(on_board yes)
		(dnp no)
		(property "Reference" "#PWR0190"
			(at 238.76 185.42 0)
			(effects
				(font
					(size 1.27 1.27)
				)
				(justify left bottom)
				(hide yes)
			)
		)
		(property "Value" "VCC"
			(at 236.855 177.8 0)
			(effects
				(font
					(size 1.27 1.27)
				)
				(justify left)
			)
		)
		(property "Footprint" ""
			(at 238.76 181.61 0)
			(effects
				(font
					(size 1.27 1.27)
				)
				(hide yes)
			)
		)
		(property "Datasheet" ""
			(at 238.76 181.61 0)
			(effects
				(font
					(size 1.27 1.27)
				)
				(hide yes)
			)
		)
		(property "Description" ""
			(at 238.76 181.61 0)
			(effects
				(font
					(size 1.27 1.27)
				)
				(hide yes)
			)
		)
		(pin "1"
		)
		(instances
			(project "jetson-agx-thor-baseboard"
				(path ""
					(reference "#PWR0190")
					(unit 1)
				)
			)
		)
	)
	(symbol
		(lib_id "antmicropower:GND")
		(at 313.69 217.17 0)
		(unit 1)
		(exclude_from_sim no)
		(in_bom yes)
		(on_board yes)
		(dnp no)
		(property "Reference" "#PWR078"
			(at 313.69 223.52 0)
			(effects
				(font
					(size 1.27 1.27)
				)
				(justify left bottom)
				(hide yes)
			)
		)
		(property "Value" "GND"
			(at 313.69 220.98 0)
			(effects
				(font
					(size 1.27 1.27)
					(thickness 0.15)
				)
			)
		)
		(property "Footprint" ""
			(at 322.58 224.79 0)
			(effects
				(font
					(size 1.27 1.27)
					(thickness 0.15)
				)
				(justify left bottom)
				(hide yes)
			)
		)
		(property "Datasheet" ""
			(at 322.58 229.87 0)
			(effects
				(font
					(size 1.27 1.27)
					(thickness 0.15)
				)
				(justify left bottom)
				(hide yes)
			)
		)
		(property "Description" ""
			(at 313.69 217.17 0)
			(effects
				(font
					(size 1.27 1.27)
				)
				(hide yes)
			)
		)
		(property "Author" "Antmicro"
			(at 322.58 224.79 0)
			(effects
				(font
					(size 1.27 1.27)
					(thickness 0.15)
				)
				(justify left bottom)
				(hide yes)
			)
		)
		(property "License" "Apache-2.0"
			(at 322.58 227.33 0)
			(effects
				(font
					(size 1.27 1.27)
					(thickness 0.15)
				)
				(justify left bottom)
				(hide yes)
			)
		)
		(pin "1"
		)
		(instances
			(project "jetson-agx-thor-baseboard"
				(path ""
					(reference "#PWR078")
					(unit 1)
				)
			)
		)
	)
	(symbol
		(lib_id "antmicropower:VCC")
		(at 228.6 181.61 0)
		(unit 1)
		(exclude_from_sim no)
		(in_bom yes)
		(on_board yes)
		(dnp no)
		(property "Reference" "#PWR0608"
			(at 228.6 185.42 0)
			(effects
				(font
					(size 1.27 1.27)
				)
				(justify left bottom)
				(hide yes)
			)
		)
		(property "Value" "+20V"
			(at 226.695 177.8 0)
			(effects
				(font
					(size 1.27 1.27)
				)
				(justify left)
			)
		)
		(property "Footprint" ""
			(at 228.6 181.61 0)
			(effects
				(font
					(size 1.27 1.27)
				)
				(hide yes)
			)
		)
		(property "Datasheet" ""
			(at 228.6 181.61 0)
			(effects
				(font
					(size 1.27 1.27)
				)
				(hide yes)
			)
		)
		(property "Description" ""
			(at 228.6 181.61 0)
			(effects
				(font
					(size 1.27 1.27)
				)
				(hide yes)
			)
		)
		(pin "1"
		)
		(instances
			(project "jetson-agx-thor-baseboard"
				(path ""
					(reference "#PWR0608")
					(unit 1)
				)
			)
		)
	)
	(symbol
		(lib_id "antmicroTestPoints:TP_0.75mm_SMD")
		(at 317.5 195.58 0)
		(unit 1)
		(exclude_from_sim no)
		(in_bom no)
		(on_board yes)
		(dnp no)
		(property "Reference" "TP75"
			(at 321.818 195.58 0)
			(effects
				(font
					(size 1.27 1.27)
				)
				(justify left)
			)
		)
		(property "Value" "TP_0.75mm_SMD"
			(at 327.66 199.39 0)
			(effects
				(font
					(size 1.27 1.27)
					(thickness 0.15)
				)
				(justify left bottom)
				(hide yes)
			)
		)
		(property "Footprint" "antmicro-footprints:TP_SMD_0.75mm"
			(at 327.66 201.93 0)
			(effects
				(font
					(size 1.27 1.27)
					(thickness 0.15)
				)
				(justify left bottom)
				(hide yes)
			)
		)
		(property "Datasheet" ""
			(at 335.28 208.28 0)
			(effects
				(font
					(size 1.27 1.27)
					(thickness 0.15)
				)
				(justify left bottom)
				(hide yes)
			)
		)
		(property "Description" "SMT test point"
			(at 317.5 195.58 0)
			(effects
				(font
					(size 1.27 1.27)
				)
				(hide yes)
			)
		)
		(property "MPN" ""
			(at 328.295 207.01 0)
			(effects
				(font
					(size 1.27 1.27)
					(thickness 0.15)
				)
				(justify left bottom)
				(hide yes)
			)
		)
		(property "Manufacturer" ""
			(at 328.295 201.93 0)
			(effects
				(font
					(size 1.27 1.27)
					(thickness 0.15)
				)
				(justify left bottom)
				(hide yes)
			)
		)
		(property "Author" "Antmicro"
			(at 327.66 204.47 0)
			(effects
				(font
					(size 1.27 1.27)
					(thickness 0.15)
				)
				(justify left bottom)
				(hide yes)
			)
		)
		(property "License" "Apache-2.0"
			(at 327.66 207.01 0)
			(effects
				(font
					(size 1.27 1.27)
					(thickness 0.15)
				)
				(justify left bottom)
				(hide yes)
			)
		)
		(pin "1"
		)
		(instances
			(project "jetson-agx-thor-baseboard"
				(path ""
					(reference "TP75")
					(unit 1)
				)
			)
		)
	)
	(symbol
		(lib_id "antmicroTestPoints:TP_0.75mm_SMD")
		(at 196.85 198.12 180)
		(unit 1)
		(exclude_from_sim no)
		(in_bom no)
		(on_board yes)
		(dnp no)
		(property "Reference" "TP131"
			(at 186.69 198.12 0)
			(effects
				(font
					(size 1.27 1.27)
				)
				(justify right)
			)
		)
		(property "Value" "TP_0.75mm_SMD"
			(at 186.69 194.31 0)
			(effects
				(font
					(size 1.27 1.27)
					(thickness 0.15)
				)
				(justify left bottom)
				(hide yes)
			)
		)
		(property "Footprint" "antmicro-footprints:TP_SMD_0.75mm"
			(at 186.69 191.77 0)
			(effects
				(font
					(size 1.27 1.27)
					(thickness 0.15)
				)
				(justify left bottom)
				(hide yes)
			)
		)
		(property "Datasheet" ""
			(at 179.07 185.42 0)
			(effects
				(font
					(size 1.27 1.27)
					(thickness 0.15)
				)
				(justify left bottom)
				(hide yes)
			)
		)
		(property "Description" "SMT test point"
			(at 196.85 198.12 0)
			(effects
				(font
					(size 1.27 1.27)
				)
				(hide yes)
			)
		)
		(property "MPN" ""
			(at 186.055 186.69 0)
			(effects
				(font
					(size 1.27 1.27)
					(thickness 0.15)
				)
				(justify left bottom)
				(hide yes)
			)
		)
		(property "Manufacturer" ""
			(at 186.055 191.77 0)
			(effects
				(font
					(size 1.27 1.27)
					(thickness 0.15)
				)
				(justify left bottom)
				(hide yes)
			)
		)
		(property "Author" "Antmicro"
			(at 186.69 189.23 0)
			(effects
				(font
					(size 1.27 1.27)
					(thickness 0.15)
				)
				(justify left bottom)
				(hide yes)
			)
		)
		(property "License" "Apache-2.0"
			(at 186.69 186.69 0)
			(effects
				(font
					(size 1.27 1.27)
					(thickness 0.15)
				)
				(justify left bottom)
				(hide yes)
			)
		)
		(pin "1"
		)
		(instances
			(project "jetson-agx-thor-baseboard"
				(path ""
					(reference "TP131")
					(unit 1)
				)
			)
		)
	)
	(symbol
		(lib_id "antmicropower:VCC")
		(at 342.9 52.07 0)
		(unit 1)
		(exclude_from_sim no)
		(in_bom yes)
		(on_board yes)
		(dnp no)
		(property "Reference" "#PWR0615"
			(at 342.9 55.88 0)
			(effects
				(font
					(size 1.27 1.27)
				)
				(justify left bottom)
				(hide yes)
			)
		)
		(property "Value" "+20V"
			(at 340.995 48.26 0)
			(effects
				(font
					(size 1.27 1.27)
				)
				(justify left)
			)
		)
		(property "Footprint" ""
			(at 342.9 52.07 0)
			(effects
				(font
					(size 1.27 1.27)
				)
				(hide yes)
			)
		)
		(property "Datasheet" ""
			(at 342.9 52.07 0)
			(effects
				(font
					(size 1.27 1.27)
				)
				(hide yes)
			)
		)
		(property "Description" ""
			(at 342.9 52.07 0)
			(effects
				(font
					(size 1.27 1.27)
				)
				(hide yes)
			)
		)
		(pin "1"
		)
		(instances
			(project "jetson-agx-thor-baseboard"
				(path ""
					(reference "#PWR0615")
					(unit 1)
				)
			)
		)
	)
	(symbol
		(lib_id "antmicropower:GND")
		(at 368.3 218.44 0)
		(unit 1)
		(exclude_from_sim no)
		(in_bom yes)
		(on_board yes)
		(dnp no)
		(property "Reference" "#PWR0104"
			(at 368.3 224.79 0)
			(effects
				(font
					(size 1.27 1.27)
				)
				(justify left bottom)
				(hide yes)
			)
		)
		(property "Value" "GND"
			(at 368.3 222.25 0)
			(effects
				(font
					(size 1.27 1.27)
					(thickness 0.15)
				)
			)
		)
		(property "Footprint" ""
			(at 377.19 226.06 0)
			(effects
				(font
					(size 1.27 1.27)
					(thickness 0.15)
				)
				(justify left bottom)
				(hide yes)
			)
		)
		(property "Datasheet" ""
			(at 377.19 231.14 0)
			(effects
				(font
					(size 1.27 1.27)
					(thickness 0.15)
				)
				(justify left bottom)
				(hide yes)
			)
		)
		(property "Description" ""
			(at 368.3 218.44 0)
			(effects
				(font
					(size 1.27 1.27)
				)
				(hide yes)
			)
		)
		(property "Author" "Antmicro"
			(at 377.19 226.06 0)
			(effects
				(font
					(size 1.27 1.27)
					(thickness 0.15)
				)
				(justify left bottom)
				(hide yes)
			)
		)
		(property "License" "Apache-2.0"
			(at 377.19 228.6 0)
			(effects
				(font
					(size 1.27 1.27)
					(thickness 0.15)
				)
				(justify left bottom)
				(hide yes)
			)
		)
		(pin "1"
		)
		(instances
			(project "jetson-agx-thor-baseboard"
				(path ""
					(reference "#PWR0104")
					(unit 1)
				)
			)
		)
	)
	(symbol
		(lib_id "antmicroTestPoints:TP_0.75mm_SMD")
		(at 196.85 195.58 180)
		(unit 1)
		(exclude_from_sim no)
		(in_bom no)
		(on_board yes)
		(dnp no)
		(property "Reference" "TP130"
			(at 186.69 195.58 0)
			(effects
				(font
					(size 1.27 1.27)
				)
				(justify right)
			)
		)
		(property "Value" "TP_0.75mm_SMD"
			(at 186.69 191.77 0)
			(effects
				(font
					(size 1.27 1.27)
					(thickness 0.15)
				)
				(justify left bottom)
				(hide yes)
			)
		)
		(property "Footprint" "antmicro-footprints:TP_SMD_0.75mm"
			(at 186.69 189.23 0)
			(effects
				(font
					(size 1.27 1.27)
					(thickness 0.15)
				)
				(justify left bottom)
				(hide yes)
			)
		)
		(property "Datasheet" ""
			(at 179.07 182.88 0)
			(effects
				(font
					(size 1.27 1.27)
					(thickness 0.15)
				)
				(justify left bottom)
				(hide yes)
			)
		)
		(property "Description" "SMT test point"
			(at 196.85 195.58 0)
			(effects
				(font
					(size 1.27 1.27)
				)
				(hide yes)
			)
		)
		(property "MPN" ""
			(at 186.055 184.15 0)
			(effects
				(font
					(size 1.27 1.27)
					(thickness 0.15)
				)
				(justify left bottom)
				(hide yes)
			)
		)
		(property "Manufacturer" ""
			(at 186.055 189.23 0)
			(effects
				(font
					(size 1.27 1.27)
					(thickness 0.15)
				)
				(justify left bottom)
				(hide yes)
			)
		)
		(property "Author" "Antmicro"
			(at 186.69 186.69 0)
			(effects
				(font
					(size 1.27 1.27)
					(thickness 0.15)
				)
				(justify left bottom)
				(hide yes)
			)
		)
		(property "License" "Apache-2.0"
			(at 186.69 184.15 0)
			(effects
				(font
					(size 1.27 1.27)
					(thickness 0.15)
				)
				(justify left bottom)
				(hide yes)
			)
		)
		(pin "1"
		)
		(instances
			(project "jetson-agx-thor-baseboard"
				(path ""
					(reference "TP130")
					(unit 1)
				)
			)
		)
	)
	(symbol
		(lib_id "antmicroTestPoints:TP_0.75mm_SMD")
		(at 367.03 210.82 0)
		(mirror y)
		(unit 1)
		(exclude_from_sim no)
		(in_bom no)
		(on_board yes)
		(dnp no)
		(property "Reference" "TP64"
			(at 365.76 207.772 0)
			(effects
				(font
					(size 1.27 1.27)
				)
				(justify left)
			)
		)
		(property "Value" "TP_0.75mm_SMD"
			(at 356.87 214.63 0)
			(effects
				(font
					(size 1.27 1.27)
					(thickness 0.15)
				)
				(justify left bottom)
				(hide yes)
			)
		)
		(property "Footprint" "antmicro-footprints:TP_SMD_0.75mm"
			(at 356.87 217.17 0)
			(effects
				(font
					(size 1.27 1.27)
					(thickness 0.15)
				)
				(justify left bottom)
				(hide yes)
			)
		)
		(property "Datasheet" ""
			(at 349.25 223.52 0)
			(effects
				(font
					(size 1.27 1.27)
					(thickness 0.15)
				)
				(justify left bottom)
				(hide yes)
			)
		)
		(property "Description" "SMT test point"
			(at 367.03 210.82 0)
			(effects
				(font
					(size 1.27 1.27)
				)
				(hide yes)
			)
		)
		(property "MPN" ""
			(at 356.235 222.25 0)
			(effects
				(font
					(size 1.27 1.27)
					(thickness 0.15)
				)
				(justify left bottom)
				(hide yes)
			)
		)
		(property "Manufacturer" ""
			(at 356.235 217.17 0)
			(effects
				(font
					(size 1.27 1.27)
					(thickness 0.15)
				)
				(justify left bottom)
				(hide yes)
			)
		)
		(property "Author" "Antmicro"
			(at 356.87 219.71 0)
			(effects
				(font
					(size 1.27 1.27)
					(thickness 0.15)
				)
				(justify left bottom)
				(hide yes)
			)
		)
		(property "License" "Apache-2.0"
			(at 356.87 222.25 0)
			(effects
				(font
					(size 1.27 1.27)
					(thickness 0.15)
				)
				(justify left bottom)
				(hide yes)
			)
		)
		(pin "1"
		)
		(instances
			(project "jetson-agx-thor-baseboard"
				(path ""
					(reference "TP64")
					(unit 1)
				)
			)
		)
	)
	(symbol
		(lib_id "antmicropower:GND")
		(at 269.24 217.17 0)
		(unit 1)
		(exclude_from_sim no)
		(in_bom yes)
		(on_board yes)
		(dnp no)
		(property "Reference" "#PWR082"
			(at 269.24 223.52 0)
			(effects
				(font
					(size 1.27 1.27)
				)
				(justify left bottom)
				(hide yes)
			)
		)
		(property "Value" "GND"
			(at 269.24 220.98 0)
			(effects
				(font
					(size 1.27 1.27)
					(thickness 0.15)
				)
			)
		)
		(property "Footprint" ""
			(at 278.13 224.79 0)
			(effects
				(font
					(size 1.27 1.27)
					(thickness 0.15)
				)
				(justify left bottom)
				(hide yes)
			)
		)
		(property "Datasheet" ""
			(at 278.13 229.87 0)
			(effects
				(font
					(size 1.27 1.27)
					(thickness 0.15)
				)
				(justify left bottom)
				(hide yes)
			)
		)
		(property "Description" ""
			(at 269.24 217.17 0)
			(effects
				(font
					(size 1.27 1.27)
				)
				(hide yes)
			)
		)
		(property "Author" "Antmicro"
			(at 278.13 224.79 0)
			(effects
				(font
					(size 1.27 1.27)
					(thickness 0.15)
				)
				(justify left bottom)
				(hide yes)
			)
		)
		(property "License" "Apache-2.0"
			(at 278.13 227.33 0)
			(effects
				(font
					(size 1.27 1.27)
					(thickness 0.15)
				)
				(justify left bottom)
				(hide yes)
			)
		)
		(pin "1"
		)
		(instances
			(project "jetson-agx-thor-baseboard"
				(path ""
					(reference "#PWR082")
					(unit 1)
				)
			)
		)
	)
	(symbol
		(lib_id "antmicroTVSDiodes:PESD5Z5_0F")
		(at 127 82.55 90)
		(mirror x)
		(unit 1)
		(exclude_from_sim no)
		(in_bom yes)
		(on_board yes)
		(dnp no)
		(property "Reference" "D11"
			(at 128.27 83.82 90)
			(effects
				(font
					(size 1.27 1.27)
				)
				(justify right)
			)
		)
		(property "Value" "PESD5Z5.0F"
			(at 142.24 104.14 0)
			(effects
				(font
					(size 1.27 1.27)
					(thickness 0.15)
				)
				(justify left bottom)
				(hide yes)
			)
		)
		(property "Footprint" "antmicro-footprints:SOD-523"
			(at 132.08 97.79 0)
			(effects
				(font
					(size 1.27 1.27)
					(thickness 0.15)
				)
				(justify left bottom)
				(hide yes)
			)
		)
		(property "Datasheet" "https://assets.nexperia.com/documents/data-sheet/PESD5Z5_0.pdf"
			(at 134.62 97.79 0)
			(effects
				(font
					(size 1.27 1.27)
					(thickness 0.15)
				)
				(justify left bottom)
				(hide yes)
			)
		)
		(property "Description" "Unidirectional TVS, 30 kV,  SOD-523, 5 V, 89 pF"
			(at 147.32 97.79 0)
			(effects
				(font
					(size 1.27 1.27)
				)
				(justify left bottom)
				(hide yes)
			)
		)
		(property "Manufacturer" "Nexperia"
			(at 137.16 97.79 0)
			(effects
				(font
					(size 1.27 1.27)
					(thickness 0.15)
				)
				(justify left bottom)
				(hide yes)
			)
		)
		(property "MPN" "PESD5Z5.0F"
			(at 139.954 86.36 90)
			(effects
				(font
					(size 1.27 1.27)
					(thickness 0.15)
				)
				(justify left bottom)
			)
		)
		(property "Author" "Antmicro"
			(at 142.24 97.79 0)
			(effects
				(font
					(size 1.27 1.27)
					(thickness 0.15)
				)
				(justify left bottom)
				(hide yes)
			)
		)
		(property "License" "Apache-2.0"
			(at 144.78 97.79 0)
			(effects
				(font
					(size 1.27 1.27)
					(thickness 0.15)
				)
				(justify left bottom)
				(hide yes)
			)
		)
		(pin "1"
		)
		(pin "2"
		)
		(instances
			(project "jetson-agx-thor-baseboard"
				(path ""
					(reference "D11")
					(unit 1)
				)
			)
		)
	)
	(symbol
		(lib_id "antmicroTestPoints:TP_0.75mm_SMD")
		(at 317.5 198.12 0)
		(unit 1)
		(exclude_from_sim no)
		(in_bom no)
		(on_board yes)
		(dnp no)
		(property "Reference" "TP9"
			(at 321.818 198.12 0)
			(effects
				(font
					(size 1.27 1.27)
				)
				(justify left)
			)
		)
		(property "Value" "TP_0.75mm_SMD"
			(at 327.66 201.93 0)
			(effects
				(font
					(size 1.27 1.27)
					(thickness 0.15)
				)
				(justify left bottom)
				(hide yes)
			)
		)
		(property "Footprint" "antmicro-footprints:TP_SMD_0.75mm"
			(at 327.66 204.47 0)
			(effects
				(font
					(size 1.27 1.27)
					(thickness 0.15)
				)
				(justify left bottom)
				(hide yes)
			)
		)
		(property "Datasheet" ""
			(at 335.28 210.82 0)
			(effects
				(font
					(size 1.27 1.27)
					(thickness 0.15)
				)
				(justify left bottom)
				(hide yes)
			)
		)
		(property "Description" "SMT test point"
			(at 317.5 198.12 0)
			(effects
				(font
					(size 1.27 1.27)
				)
				(hide yes)
			)
		)
		(property "MPN" ""
			(at 328.295 209.55 0)
			(effects
				(font
					(size 1.27 1.27)
					(thickness 0.15)
				)
				(justify left bottom)
				(hide yes)
			)
		)
		(property "Manufacturer" ""
			(at 328.295 204.47 0)
			(effects
				(font
					(size 1.27 1.27)
					(thickness 0.15)
				)
				(justify left bottom)
				(hide yes)
			)
		)
		(property "Author" "Antmicro"
			(at 327.66 207.01 0)
			(effects
				(font
					(size 1.27 1.27)
					(thickness 0.15)
				)
				(justify left bottom)
				(hide yes)
			)
		)
		(property "License" "Apache-2.0"
			(at 327.66 209.55 0)
			(effects
				(font
					(size 1.27 1.27)
					(thickness 0.15)
				)
				(justify left bottom)
				(hide yes)
			)
		)
		(pin "1"
		)
		(instances
			(project "jetson-agx-thor-baseboard"
				(path ""
					(reference "TP9")
					(unit 1)
				)
			)
		)
	)
	(symbol
		(lib_id "antmicroWire2BoardConnectors:Molex_Mini-Fit_2x3_50362462")
		(at 205.74 35.56 0)
		(mirror y)
		(unit 1)
		(exclude_from_sim no)
		(in_bom yes)
		(on_board yes)
		(dnp no)
		(property "Reference" "J2"
			(at 199.644 31.75 0)
			(effects
				(font
					(size 1.27 1.27)
					(thickness 0.15)
				)
			)
		)
		(property "Value" "Molex_Mini-Fit_2x3_50362462"
			(at 176.53 43.18 0)
			(effects
				(font
					(size 1.27 1.27)
					(thickness 0.15)
				)
				(justify left bottom)
				(hide yes)
			)
		)
		(property "Footprint" "antmicro-footprints:Molex_Mini-Fit_2x3_50362462"
			(at 176.53 45.72 0)
			(effects
				(font
					(size 1.27 1.27)
					(thickness 0.15)
				)
				(justify left bottom)
				(hide yes)
			)
		)
		(property "Datasheet" "https://www.molex.com/content/dam/molex/molex-dot-com/products/automated/en-us/salesdrawingpdf/556/5569/050362462_sd.pdf?inline"
			(at 176.53 48.26 0)
			(effects
				(font
					(size 1.27 1.27)
					(thickness 0.15)
				)
				(justify left bottom)
				(hide yes)
			)
		)
		(property "Description" "Pin Header, Wire-to-Board, 2 Rows, 6 Contacts, Through Hole Right-Angle, Mini-Fit, 13A/pin, 600V, 4.2mm"
			(at 176.53 58.42 0)
			(effects
				(font
					(size 1.27 1.27)
				)
				(justify left bottom)
				(hide yes)
			)
		)
		(property "MPN" "50362462"
			(at 200.152 44.704 0)
			(effects
				(font
					(size 1.27 1.27)
					(thickness 0.15)
				)
			)
		)
		(property "Manufacturer" "Molex"
			(at 176.53 50.8 0)
			(effects
				(font
					(size 1.27 1.27)
					(thickness 0.15)
				)
				(justify left bottom)
				(hide yes)
			)
		)
		(property "Author" "Antmicro"
			(at 176.53 53.34 0)
			(effects
				(font
					(size 1.27 1.27)
					(thickness 0.15)
				)
				(justify left bottom)
				(hide yes)
			)
		)
		(property "License" "Apache-2.0"
			(at 176.53 55.88 0)
			(effects
				(font
					(size 1.27 1.27)
					(thickness 0.15)
				)
				(justify left bottom)
				(hide yes)
			)
		)
		(pin "1"
		)
		(pin "6"
		)
		(pin "4"
		)
		(pin "2"
		)
		(pin "3"
		)
		(pin "5"
		)
		(instances
			(project ""
				(path ""
					(reference "J2")
					(unit 1)
				)
			)
		)
	)
	(symbol
		(lib_id "antmicroResistors0402:R_2k2_0402")
		(at 238.76 209.55 90)
		(unit 1)
		(exclude_from_sim no)
		(in_bom yes)
		(on_board yes)
		(dnp no)
		(fields_autoplaced yes)
		(property "Reference" "R27"
			(at 241.3 205.74 90)
			(effects
				(font
					(size 1.27 1.27)
					(thickness 0.15)
				)
				(justify right)
			)
		)
		(property "Value" "R_2k2_0402"
			(at 251.46 189.23 0)
			(effects
				(font
					(size 1.27 1.27)
					(thickness 0.15)
				)
				(justify left bottom)
				(hide yes)
			)
		)
		(property "Footprint" "antmicro-footprints:R_0402_1005Metric"
			(at 254 189.23 0)
			(effects
				(font
					(size 1.27 1.27)
					(thickness 0.15)
				)
				(justify left bottom)
				(hide yes)
			)
		)
		(property "Datasheet" "https://www.bourns.com/docs/product-datasheets/cr.pdf"
			(at 256.54 189.23 0)
			(effects
				(font
					(size 1.27 1.27)
					(thickness 0.15)
				)
				(justify left bottom)
				(hide yes)
			)
		)
		(property "Description" "SMD Chip Resistor, 2.2 kohm, ± 1%, 62.5 mW, 0402 [1005 Metric], Thick Film, General Purpose"
			(at 238.76 209.55 0)
			(effects
				(font
					(size 1.27 1.27)
				)
				(hide yes)
			)
		)
		(property "MPN" "CR0402-FX-2201GLF"
			(at 259.08 189.23 0)
			(effects
				(font
					(size 1.27 1.27)
					(thickness 0.15)
				)
				(justify left bottom)
				(hide yes)
			)
		)
		(property "Manufacturer" "Bourns"
			(at 261.62 189.23 0)
			(effects
				(font
					(size 1.27 1.27)
					(thickness 0.15)
				)
				(justify left bottom)
				(hide yes)
			)
		)
		(property "License" "Apache-2.0"
			(at 264.16 189.23 0)
			(effects
				(font
					(size 1.27 1.27)
					(thickness 0.15)
				)
				(justify left bottom)
				(hide yes)
			)
		)
		(property "Author" "Antmicro"
			(at 266.7 189.23 0)
			(effects
				(font
					(size 1.27 1.27)
					(thickness 0.15)
				)
				(justify left bottom)
				(hide yes)
			)
		)
		(property "Val" "2k2"
			(at 241.3 208.28 90)
			(effects
				(font
					(size 1.27 1.27)
					(thickness 0.15)
				)
				(justify right)
			)
		)
		(property "Tolerance" "1%"
			(at 248.92 189.23 0)
			(effects
				(font
					(size 1.27 1.27)
				)
				(justify left bottom)
				(hide yes)
			)
		)
		(pin "2"
		)
		(pin "1"
		)
		(instances
			(project "jetson-agx-thor-baseboard"
				(path ""
					(reference "R27")
					(unit 1)
				)
			)
		)
	)
	(symbol
		(lib_id "antmicroCapacitors0402:C_100n_0402")
		(at 275.59 44.45 90)
		(unit 1)
		(exclude_from_sim no)
		(in_bom yes)
		(on_board yes)
		(dnp no)
		(property "Reference" "C357"
			(at 274.066 40.64 90)
			(effects
				(font
					(size 1.27 1.27)
					(thickness 0.15)
				)
				(justify left)
			)
		)
		(property "Value" "C_100n_0402"
			(at 298.45 29.21 0)
			(effects
				(font
					(size 1.27 1.27)
					(thickness 0.15)
				)
				(justify left bottom)
				(hide yes)
			)
		)
		(property "Footprint" "antmicro-footprints:C_0402_1005Metric"
			(at 300.99 29.21 0)
			(effects
				(font
					(size 1.27 1.27)
					(thickness 0.15)
				)
				(justify left bottom)
				(hide yes)
			)
		)
		(property "Datasheet" "https://www.murata.com/products/productdetail?partno=GRM155R61H104KE14%23"
			(at 303.53 29.21 0)
			(effects
				(font
					(size 1.27 1.27)
					(thickness 0.15)
				)
				(justify left bottom)
				(hide yes)
			)
		)
		(property "Description" "SMD Multilayer Ceramic Capacitor, 0.1 µF, 50 V, 0402 [1005 Metric], ± 10%, X5R, GRM Series"
			(at 275.59 44.45 0)
			(effects
				(font
					(size 1.27 1.27)
				)
				(hide yes)
			)
		)
		(property "MPN" "GRM155R61H104KE14D"
			(at 306.07 29.21 0)
			(effects
				(font
					(size 1.27 1.27)
					(thickness 0.15)
				)
				(justify left bottom)
				(hide yes)
			)
		)
		(property "Val" "100n"
			(at 274.066 43.18 90)
			(effects
				(font
					(size 1.27 1.27)
					(thickness 0.15)
				)
				(justify left)
			)
		)
		(property "Voltage" "50V"
			(at 285.75 29.21 0)
			(effects
				(font
					(size 1.27 1.27)
					(thickness 0.15)
				)
				(justify left bottom)
				(hide yes)
			)
		)
		(property "Dielectric" "X5R"
			(at 288.29 29.21 0)
			(effects
				(font
					(size 1.27 1.27)
					(thickness 0.15)
				)
				(justify left bottom)
				(hide yes)
			)
		)
		(property "Manufacturer" "Murata"
			(at 290.83 29.21 0)
			(effects
				(font
					(size 1.27 1.27)
					(thickness 0.15)
				)
				(justify left bottom)
				(hide yes)
			)
		)
		(property "License" "Apache-2.0"
			(at 293.37 29.21 0)
			(effects
				(font
					(size 1.27 1.27)
					(thickness 0.15)
				)
				(justify left bottom)
				(hide yes)
			)
		)
		(property "Author" "Antmicro"
			(at 295.91 29.21 0)
			(effects
				(font
					(size 1.27 1.27)
					(thickness 0.15)
				)
				(justify left bottom)
				(hide yes)
			)
		)
		(pin "1"
		)
		(pin "2"
		)
		(instances
			(project "jetson-agx-thor-baseboard"
				(path ""
					(reference "C357")
					(unit 1)
				)
			)
		)
	)
	(symbol
		(lib_id "antmicroTransistorsFETsMOSFETsSingle:SISS05DN-T1-GE3")
		(at 251.46 41.91 90)
		(unit 1)
		(exclude_from_sim no)
		(in_bom yes)
		(on_board yes)
		(dnp no)
		(property "Reference" "Q32"
			(at 249.174 29.718 90)
			(effects
				(font
					(size 1.27 1.27)
					(thickness 0.15)
				)
			)
		)
		(property "Value" "SISS05DN-T1-GE3"
			(at 261.62 26.67 0)
			(effects
				(font
					(size 1.27 1.27)
					(thickness 0.15)
				)
				(justify left bottom)
				(hide yes)
			)
		)
		(property "Footprint" "antmicro-footprints:Vishay_PowerPAK_1212-8_Single"
			(at 264.16 26.67 0)
			(effects
				(font
					(size 1.27 1.27)
					(thickness 0.15)
				)
				(justify left bottom)
				(hide yes)
			)
		)
		(property "Datasheet" "https://www.vishay.com/docs/77029/siss05dn.pdf"
			(at 266.7 26.67 0)
			(effects
				(font
					(size 1.27 1.27)
					(thickness 0.15)
				)
				(justify left bottom)
				(hide yes)
			)
		)
		(property "Description" "Power MOSFET, P Channel, 30 V, 108 A, 0.0035 ohm, PowerPAK 1212, Surface Mount"
			(at 269.24 26.67 0)
			(effects
				(font
					(size 1.27 1.27)
					(thickness 0.15)
				)
				(justify left bottom)
				(hide yes)
			)
		)
		(property "MPN" "SISS05DN-T1-GE3"
			(at 249.174 32.258 90)
			(effects
				(font
					(size 1.27 1.27)
					(thickness 0.15)
				)
			)
		)
		(property "Manufacturer" "Vishay"
			(at 271.78 26.67 0)
			(effects
				(font
					(size 1.27 1.27)
					(thickness 0.15)
				)
				(justify left bottom)
				(hide yes)
			)
		)
		(property "Author" "Antmicro"
			(at 274.32 26.67 0)
			(effects
				(font
					(size 1.27 1.27)
					(thickness 0.15)
				)
				(justify left bottom)
				(hide yes)
			)
		)
		(property "License" "Apache-2.0"
			(at 276.86 26.67 0)
			(effects
				(font
					(size 1.27 1.27)
					(thickness 0.15)
				)
				(justify left bottom)
				(hide yes)
			)
		)
		(pin "1"
		)
		(pin "4"
		)
		(pin "3"
		)
		(pin "5"
		)
		(pin "2"
		)
		(instances
			(project "jetson-agx-thor-baseboard"
				(path ""
					(reference "Q32")
					(unit 1)
				)
			)
		)
	)
	(symbol
		(lib_id "antmicropower:PWR_FLAG")
		(at 290.83 34.29 0)
		(unit 1)
		(exclude_from_sim no)
		(in_bom yes)
		(on_board yes)
		(dnp no)
		(property "Reference" "#FLG017"
			(at 290.83 32.385 0)
			(effects
				(font
					(size 1.27 1.27)
				)
				(hide yes)
			)
		)
		(property "Value" "PWR_FLAG"
			(at 289.56 30.48 0)
			(effects
				(font
					(size 1.27 1.27)
				)
			)
		)
		(property "Footprint" ""
			(at 290.83 34.29 0)
			(effects
				(font
					(size 1.27 1.27)
				)
				(hide yes)
			)
		)
		(property "Datasheet" ""
			(at 290.83 34.29 0)
			(effects
				(font
					(size 1.27 1.27)
				)
				(hide yes)
			)
		)
		(property "Description" ""
			(at 290.83 34.29 0)
			(effects
				(font
					(size 1.27 1.27)
				)
				(hide yes)
			)
		)
		(pin "1"
		)
		(instances
			(project "jetson-agx-thor-baseboard"
				(path ""
					(reference "#FLG017")
					(unit 1)
				)
			)
		)
	)
	(symbol
		(lib_id "antmicroCapacitors0402:C_1u_25V_0402")
		(at 383.54 116.84 90)
		(unit 1)
		(exclude_from_sim no)
		(in_bom yes)
		(on_board yes)
		(dnp no)
		(fields_autoplaced yes)
		(property "Reference" "C266"
			(at 386.08 113.0236 90)
			(effects
				(font
					(size 1.27 1.27)
					(thickness 0.15)
				)
				(justify right)
			)
		)
		(property "Value" "C_1u_25V_0402"
			(at 393.7 96.52 0)
			(effects
				(font
					(size 1.27 1.27)
					(thickness 0.15)
				)
				(justify left bottom)
				(hide yes)
			)
		)
		(property "Footprint" "antmicro-footprints:C_0402_1005Metric"
			(at 396.24 96.52 0)
			(effects
				(font
					(size 1.27 1.27)
					(thickness 0.15)
				)
				(justify left bottom)
				(hide yes)
			)
		)
		(property "Datasheet" "https://www.murata.com/products/productdetail?partno=GRM155R61E105KE11%23"
			(at 398.78 96.52 0)
			(effects
				(font
					(size 1.27 1.27)
					(thickness 0.15)
				)
				(justify left bottom)
				(hide yes)
			)
		)
		(property "Description" "SMD Multilayer Ceramic Capacitor, 1 µF, 25 V, 0402 [1005 Metric], ± 10%, X5R, GRM Series"
			(at 383.54 116.84 0)
			(effects
				(font
					(size 1.27 1.27)
				)
				(hide yes)
			)
		)
		(property "MPN" "GRM155R61E105KE11J"
			(at 401.32 96.52 0)
			(effects
				(font
					(size 1.27 1.27)
					(thickness 0.15)
				)
				(justify left bottom)
				(hide yes)
			)
		)
		(property "Manufacturer" "Murata"
			(at 403.86 96.52 0)
			(effects
				(font
					(size 1.27 1.27)
					(thickness 0.15)
				)
				(justify left bottom)
				(hide yes)
			)
		)
		(property "License" "Apache-2.0"
			(at 406.4 96.52 0)
			(effects
				(font
					(size 1.27 1.27)
					(thickness 0.15)
				)
				(justify left bottom)
				(hide yes)
			)
		)
		(property "Author" "Antmicro"
			(at 408.94 96.52 0)
			(effects
				(font
					(size 1.27 1.27)
					(thickness 0.15)
				)
				(justify left bottom)
				(hide yes)
			)
		)
		(property "Val" "1u"
			(at 386.08 115.5636 90)
			(effects
				(font
					(size 1.27 1.27)
					(thickness 0.15)
				)
				(justify right)
			)
		)
		(property "Voltage" "25V"
			(at 411.48 96.52 0)
			(effects
				(font
					(size 1.27 1.27)
				)
				(justify left bottom)
				(hide yes)
			)
		)
		(property "Dielectric" "X5R"
			(at 414.02 96.52 0)
			(effects
				(font
					(size 1.27 1.27)
				)
				(justify left bottom)
				(hide yes)
			)
		)
		(pin "1"
		)
		(pin "2"
		)
		(instances
			(project "jetson-agx-thor-baseboard"
				(path ""
					(reference "C266")
					(unit 1)
				)
			)
		)
	)
	(symbol
		(lib_id "antmicropower:GND")
		(at 308.61 107.95 0)
		(unit 1)
		(exclude_from_sim no)
		(in_bom yes)
		(on_board yes)
		(dnp no)
		(property "Reference" "#PWR0599"
			(at 308.61 114.3 0)
			(effects
				(font
					(size 1.27 1.27)
				)
				(justify left bottom)
				(hide yes)
			)
		)
		(property "Value" "GND"
			(at 308.61 111.76 0)
			(effects
				(font
					(size 1.27 1.27)
					(thickness 0.15)
				)
			)
		)
		(property "Footprint" ""
			(at 317.5 115.57 0)
			(effects
				(font
					(size 1.27 1.27)
					(thickness 0.15)
				)
				(justify left bottom)
				(hide yes)
			)
		)
		(property "Datasheet" ""
			(at 317.5 120.65 0)
			(effects
				(font
					(size 1.27 1.27)
					(thickness 0.15)
				)
				(justify left bottom)
				(hide yes)
			)
		)
		(property "Description" ""
			(at 308.61 107.95 0)
			(effects
				(font
					(size 1.27 1.27)
				)
				(hide yes)
			)
		)
		(property "Author" "Antmicro"
			(at 317.5 115.57 0)
			(effects
				(font
					(size 1.27 1.27)
					(thickness 0.15)
				)
				(justify left bottom)
				(hide yes)
			)
		)
		(property "License" "Apache-2.0"
			(at 317.5 118.11 0)
			(effects
				(font
					(size 1.27 1.27)
					(thickness 0.15)
				)
				(justify left bottom)
				(hide yes)
			)
		)
		(pin "1"
		)
		(instances
			(project "jetson-agx-thor-baseboard"
				(path ""
					(reference "#PWR0599")
					(unit 1)
				)
			)
		)
	)
	(symbol
		(lib_id "antmicropower:GND")
		(at 218.44 217.17 0)
		(unit 1)
		(exclude_from_sim no)
		(in_bom yes)
		(on_board yes)
		(dnp no)
		(property "Reference" "#PWR0192"
			(at 218.44 223.52 0)
			(effects
				(font
					(size 1.27 1.27)
				)
				(justify left bottom)
				(hide yes)
			)
		)
		(property "Value" "GND"
			(at 218.44 220.98 0)
			(effects
				(font
					(size 1.27 1.27)
					(thickness 0.15)
				)
			)
		)
		(property "Footprint" ""
			(at 227.33 224.79 0)
			(effects
				(font
					(size 1.27 1.27)
					(thickness 0.15)
				)
				(justify left bottom)
				(hide yes)
			)
		)
		(property "Datasheet" ""
			(at 227.33 229.87 0)
			(effects
				(font
					(size 1.27 1.27)
					(thickness 0.15)
				)
				(justify left bottom)
				(hide yes)
			)
		)
		(property "Description" ""
			(at 218.44 217.17 0)
			(effects
				(font
					(size 1.27 1.27)
				)
				(hide yes)
			)
		)
		(property "Author" "Antmicro"
			(at 227.33 224.79 0)
			(effects
				(font
					(size 1.27 1.27)
					(thickness 0.15)
				)
				(justify left bottom)
				(hide yes)
			)
		)
		(property "License" "Apache-2.0"
			(at 227.33 227.33 0)
			(effects
				(font
					(size 1.27 1.27)
					(thickness 0.15)
				)
				(justify left bottom)
				(hide yes)
			)
		)
		(pin "1"
		)
		(instances
			(project "jetson-agx-thor-baseboard"
				(path ""
					(reference "#PWR0192")
					(unit 1)
				)
			)
		)
	)
	(symbol
		(lib_id "antmicropower:VCC")
		(at 60.96 78.74 0)
		(unit 1)
		(exclude_from_sim no)
		(in_bom yes)
		(on_board yes)
		(dnp no)
		(property "Reference" "#PWR0134"
			(at 60.96 82.55 0)
			(effects
				(font
					(size 1.27 1.27)
				)
				(justify left bottom)
				(hide yes)
			)
		)
		(property "Value" "+5V_AON"
			(at 56.134 74.422 0)
			(effects
				(font
					(size 1.27 1.27)
				)
				(justify left)
			)
		)
		(property "Footprint" ""
			(at 60.96 78.74 0)
			(effects
				(font
					(size 1.27 1.27)
				)
				(hide yes)
			)
		)
		(property "Datasheet" ""
			(at 60.96 78.74 0)
			(effects
				(font
					(size 1.27 1.27)
				)
				(hide yes)
			)
		)
		(property "Description" ""
			(at 60.96 78.74 0)
			(effects
				(font
					(size 1.27 1.27)
				)
				(hide yes)
			)
		)
		(pin "1"
		)
		(instances
			(project "jetson-agx-thor-baseboard"
				(path ""
					(reference "#PWR0134")
					(unit 1)
				)
			)
		)
	)
	(symbol
		(lib_id "antmicropower:PWR_FLAG")
		(at 132.08 81.28 270)
		(unit 1)
		(exclude_from_sim no)
		(in_bom yes)
		(on_board yes)
		(dnp no)
		(property "Reference" "#FLG07"
			(at 133.985 81.28 0)
			(effects
				(font
					(size 1.27 1.27)
				)
				(hide yes)
			)
		)
		(property "Value" "PWR_FLAG"
			(at 140.462 81.28 90)
			(effects
				(font
					(size 1.27 1.27)
				)
			)
		)
		(property "Footprint" ""
			(at 132.08 81.28 0)
			(effects
				(font
					(size 1.27 1.27)
				)
				(hide yes)
			)
		)
		(property "Datasheet" ""
			(at 132.08 81.28 0)
			(effects
				(font
					(size 1.27 1.27)
				)
				(hide yes)
			)
		)
		(property "Description" ""
			(at 132.08 81.28 0)
			(effects
				(font
					(size 1.27 1.27)
				)
				(hide yes)
			)
		)
		(pin "1"
		)
		(instances
			(project "jetson-agx-thor-baseboard"
				(path ""
					(reference "#FLG07")
					(unit 1)
				)
			)
		)
	)
	(symbol
		(lib_id "antmicropower:VCC")
		(at 325.12 85.09 0)
		(unit 1)
		(exclude_from_sim no)
		(in_bom yes)
		(on_board yes)
		(dnp no)
		(property "Reference" "#PWR0633"
			(at 325.12 88.9 0)
			(effects
				(font
					(size 1.27 1.27)
				)
				(justify left bottom)
				(hide yes)
			)
		)
		(property "Value" "VCC"
			(at 323.215 81.28 0)
			(effects
				(font
					(size 1.27 1.27)
				)
				(justify left)
			)
		)
		(property "Footprint" ""
			(at 325.12 85.09 0)
			(effects
				(font
					(size 1.27 1.27)
				)
				(hide yes)
			)
		)
		(property "Datasheet" ""
			(at 325.12 85.09 0)
			(effects
				(font
					(size 1.27 1.27)
				)
				(hide yes)
			)
		)
		(property "Description" ""
			(at 325.12 85.09 0)
			(effects
				(font
					(size 1.27 1.27)
				)
				(hide yes)
			)
		)
		(pin "1"
		)
		(instances
			(project "jetson-agx-thor-baseboard"
				(path ""
					(reference "#PWR0633")
					(unit 1)
				)
			)
		)
	)
	(symbol
		(lib_id "antmicropower:GND")
		(at 281.94 144.78 0)
		(unit 1)
		(exclude_from_sim no)
		(in_bom yes)
		(on_board yes)
		(dnp no)
		(property "Reference" "#PWR0600"
			(at 281.94 151.13 0)
			(effects
				(font
					(size 1.27 1.27)
				)
				(justify left bottom)
				(hide yes)
			)
		)
		(property "Value" "GND"
			(at 281.94 148.59 0)
			(effects
				(font
					(size 1.27 1.27)
					(thickness 0.15)
				)
			)
		)
		(property "Footprint" ""
			(at 290.83 152.4 0)
			(effects
				(font
					(size 1.27 1.27)
					(thickness 0.15)
				)
				(justify left bottom)
				(hide yes)
			)
		)
		(property "Datasheet" ""
			(at 290.83 157.48 0)
			(effects
				(font
					(size 1.27 1.27)
					(thickness 0.15)
				)
				(justify left bottom)
				(hide yes)
			)
		)
		(property "Description" ""
			(at 281.94 144.78 0)
			(effects
				(font
					(size 1.27 1.27)
				)
				(hide yes)
			)
		)
		(property "Author" "Antmicro"
			(at 290.83 152.4 0)
			(effects
				(font
					(size 1.27 1.27)
					(thickness 0.15)
				)
				(justify left bottom)
				(hide yes)
			)
		)
		(property "License" "Apache-2.0"
			(at 290.83 154.94 0)
			(effects
				(font
					(size 1.27 1.27)
					(thickness 0.15)
				)
				(justify left bottom)
				(hide yes)
			)
		)
		(pin "1"
		)
		(instances
			(project "jetson-agx-thor-baseboard"
				(path ""
					(reference "#PWR0600")
					(unit 1)
				)
			)
		)
	)
	(symbol
		(lib_id "antmicroCapacitors0402:C_100n_0402")
		(at 351.79 77.47 90)
		(unit 1)
		(exclude_from_sim no)
		(in_bom yes)
		(on_board yes)
		(dnp no)
		(fields_autoplaced yes)
		(property "Reference" "C263"
			(at 349.25 73.6536 90)
			(effects
				(font
					(size 1.27 1.27)
					(thickness 0.15)
				)
				(justify left)
			)
		)
		(property "Value" "C_100n_0402"
			(at 374.65 62.23 0)
			(effects
				(font
					(size 1.27 1.27)
					(thickness 0.15)
				)
				(justify left bottom)
				(hide yes)
			)
		)
		(property "Footprint" "antmicro-footprints:C_0402_1005Metric"
			(at 377.19 62.23 0)
			(effects
				(font
					(size 1.27 1.27)
					(thickness 0.15)
				)
				(justify left bottom)
				(hide yes)
			)
		)
		(property "Datasheet" "https://www.murata.com/products/productdetail?partno=GRM155R61H104KE14%23"
			(at 379.73 62.23 0)
			(effects
				(font
					(size 1.27 1.27)
					(thickness 0.15)
				)
				(justify left bottom)
				(hide yes)
			)
		)
		(property "Description" "SMD Multilayer Ceramic Capacitor, 0.1 µF, 50 V, 0402 [1005 Metric], ± 10%, X5R, GRM Series"
			(at 351.79 77.47 0)
			(effects
				(font
					(size 1.27 1.27)
				)
				(hide yes)
			)
		)
		(property "MPN" "GRM155R61H104KE14D"
			(at 382.27 62.23 0)
			(effects
				(font
					(size 1.27 1.27)
					(thickness 0.15)
				)
				(justify left bottom)
				(hide yes)
			)
		)
		(property "Val" "100n"
			(at 349.25 76.1936 90)
			(effects
				(font
					(size 1.27 1.27)
					(thickness 0.15)
				)
				(justify left)
			)
		)
		(property "Voltage" "50V"
			(at 361.95 62.23 0)
			(effects
				(font
					(size 1.27 1.27)
					(thickness 0.15)
				)
				(justify left bottom)
				(hide yes)
			)
		)
		(property "Dielectric" "X5R"
			(at 364.49 62.23 0)
			(effects
				(font
					(size 1.27 1.27)
					(thickness 0.15)
				)
				(justify left bottom)
				(hide yes)
			)
		)
		(property "Manufacturer" "Murata"
			(at 367.03 62.23 0)
			(effects
				(font
					(size 1.27 1.27)
					(thickness 0.15)
				)
				(justify left bottom)
				(hide yes)
			)
		)
		(property "License" "Apache-2.0"
			(at 369.57 62.23 0)
			(effects
				(font
					(size 1.27 1.27)
					(thickness 0.15)
				)
				(justify left bottom)
				(hide yes)
			)
		)
		(property "Author" "Antmicro"
			(at 372.11 62.23 0)
			(effects
				(font
					(size 1.27 1.27)
					(thickness 0.15)
				)
				(justify left bottom)
				(hide yes)
			)
		)
		(pin "1"
		)
		(pin "2"
		)
		(instances
			(project "jetson-agx-thor-baseboard"
				(path ""
					(reference "C263")
					(unit 1)
				)
			)
		)
	)
	(symbol
		(lib_id "antmicroTestPoints:TP_0.75mm_SMD")
		(at 196.85 200.66 180)
		(unit 1)
		(exclude_from_sim no)
		(in_bom no)
		(on_board yes)
		(dnp no)
		(property "Reference" "TP132"
			(at 186.69 200.66 0)
			(effects
				(font
					(size 1.27 1.27)
				)
				(justify right)
			)
		)
		(property "Value" "TP_0.75mm_SMD"
			(at 186.69 196.85 0)
			(effects
				(font
					(size 1.27 1.27)
					(thickness 0.15)
				)
				(justify left bottom)
				(hide yes)
			)
		)
		(property "Footprint" "antmicro-footprints:TP_SMD_0.75mm"
			(at 186.69 194.31 0)
			(effects
				(font
					(size 1.27 1.27)
					(thickness 0.15)
				)
				(justify left bottom)
				(hide yes)
			)
		)
		(property "Datasheet" ""
			(at 179.07 187.96 0)
			(effects
				(font
					(size 1.27 1.27)
					(thickness 0.15)
				)
				(justify left bottom)
				(hide yes)
			)
		)
		(property "Description" "SMT test point"
			(at 196.85 200.66 0)
			(effects
				(font
					(size 1.27 1.27)
				)
				(hide yes)
			)
		)
		(property "MPN" ""
			(at 186.055 189.23 0)
			(effects
				(font
					(size 1.27 1.27)
					(thickness 0.15)
				)
				(justify left bottom)
				(hide yes)
			)
		)
		(property "Manufacturer" ""
			(at 186.055 194.31 0)
			(effects
				(font
					(size 1.27 1.27)
					(thickness 0.15)
				)
				(justify left bottom)
				(hide yes)
			)
		)
		(property "Author" "Antmicro"
			(at 186.69 191.77 0)
			(effects
				(font
					(size 1.27 1.27)
					(thickness 0.15)
				)
				(justify left bottom)
				(hide yes)
			)
		)
		(property "License" "Apache-2.0"
			(at 186.69 189.23 0)
			(effects
				(font
					(size 1.27 1.27)
					(thickness 0.15)
				)
				(justify left bottom)
				(hide yes)
			)
		)
		(pin "1"
		)
		(instances
			(project "jetson-agx-thor-baseboard"
				(path ""
					(reference "TP132")
					(unit 1)
				)
			)
		)
	)
	(symbol
		(lib_id "antmicroTestPoints:TP_0.75mm_SMD")
		(at 317.5 193.04 0)
		(unit 1)
		(exclude_from_sim no)
		(in_bom no)
		(on_board yes)
		(dnp no)
		(property "Reference" "TP7"
			(at 321.818 193.04 0)
			(effects
				(font
					(size 1.27 1.27)
				)
				(justify left)
			)
		)
		(property "Value" "TP_0.75mm_SMD"
			(at 327.66 196.85 0)
			(effects
				(font
					(size 1.27 1.27)
					(thickness 0.15)
				)
				(justify left bottom)
				(hide yes)
			)
		)
		(property "Footprint" "antmicro-footprints:TP_SMD_0.75mm"
			(at 327.66 199.39 0)
			(effects
				(font
					(size 1.27 1.27)
					(thickness 0.15)
				)
				(justify left bottom)
				(hide yes)
			)
		)
		(property "Datasheet" ""
			(at 335.28 205.74 0)
			(effects
				(font
					(size 1.27 1.27)
					(thickness 0.15)
				)
				(justify left bottom)
				(hide yes)
			)
		)
		(property "Description" "SMT test point"
			(at 317.5 193.04 0)
			(effects
				(font
					(size 1.27 1.27)
				)
				(hide yes)
			)
		)
		(property "MPN" ""
			(at 328.295 204.47 0)
			(effects
				(font
					(size 1.27 1.27)
					(thickness 0.15)
				)
				(justify left bottom)
				(hide yes)
			)
		)
		(property "Manufacturer" ""
			(at 328.295 199.39 0)
			(effects
				(font
					(size 1.27 1.27)
					(thickness 0.15)
				)
				(justify left bottom)
				(hide yes)
			)
		)
		(property "Author" "Antmicro"
			(at 327.66 201.93 0)
			(effects
				(font
					(size 1.27 1.27)
					(thickness 0.15)
				)
				(justify left bottom)
				(hide yes)
			)
		)
		(property "License" "Apache-2.0"
			(at 327.66 204.47 0)
			(effects
				(font
					(size 1.27 1.27)
					(thickness 0.15)
				)
				(justify left bottom)
				(hide yes)
			)
		)
		(pin "1"
		)
		(instances
			(project "jetson-agx-thor-baseboard"
				(path ""
					(reference "TP7")
					(unit 1)
				)
			)
		)
	)
	(symbol
		(lib_id "antmicropower:PWR_FLAG")
		(at 193.04 34.29 0)
		(mirror y)
		(unit 1)
		(exclude_from_sim no)
		(in_bom yes)
		(on_board yes)
		(dnp no)
		(property "Reference" "#FLG012"
			(at 193.04 32.385 0)
			(effects
				(font
					(size 1.27 1.27)
				)
				(hide yes)
			)
		)
		(property "Value" "PWR_FLAG"
			(at 193.04 30.48 0)
			(effects
				(font
					(size 1.27 1.27)
				)
			)
		)
		(property "Footprint" ""
			(at 193.04 34.29 0)
			(effects
				(font
					(size 1.27 1.27)
				)
				(hide yes)
			)
		)
		(property "Datasheet" ""
			(at 193.04 34.29 0)
			(effects
				(font
					(size 1.27 1.27)
				)
				(hide yes)
			)
		)
		(property "Description" ""
			(at 193.04 34.29 0)
			(effects
				(font
					(size 1.27 1.27)
				)
				(hide yes)
			)
		)
		(pin "1"
		)
		(instances
			(project "jetson-agx-thor-baseboard"
				(path ""
					(reference "#FLG012")
					(unit 1)
				)
			)
		)
	)
	(symbol
		(lib_id "antmicropower:GND")
		(at 127 88.9 0)
		(unit 1)
		(exclude_from_sim no)
		(in_bom yes)
		(on_board yes)
		(dnp no)
		(property "Reference" "#PWR0159"
			(at 127 95.25 0)
			(effects
				(font
					(size 1.27 1.27)
				)
				(justify left bottom)
				(hide yes)
			)
		)
		(property "Value" "GND"
			(at 127 92.71 0)
			(effects
				(font
					(size 1.27 1.27)
					(thickness 0.15)
				)
			)
		)
		(property "Footprint" ""
			(at 135.89 96.52 0)
			(effects
				(font
					(size 1.27 1.27)
					(thickness 0.15)
				)
				(justify left bottom)
				(hide yes)
			)
		)
		(property "Datasheet" ""
			(at 135.89 101.6 0)
			(effects
				(font
					(size 1.27 1.27)
					(thickness 0.15)
				)
				(justify left bottom)
				(hide yes)
			)
		)
		(property "Description" ""
			(at 127 88.9 0)
			(effects
				(font
					(size 1.27 1.27)
				)
				(hide yes)
			)
		)
		(property "Author" "Antmicro"
			(at 135.89 96.52 0)
			(effects
				(font
					(size 1.27 1.27)
					(thickness 0.15)
				)
				(justify left bottom)
				(hide yes)
			)
		)
		(property "License" "Apache-2.0"
			(at 135.89 99.06 0)
			(effects
				(font
					(size 1.27 1.27)
					(thickness 0.15)
				)
				(justify left bottom)
				(hide yes)
			)
		)
		(pin "1"
		)
		(instances
			(project "jetson-agx-thor-baseboard"
				(path ""
					(reference "#PWR0159")
					(unit 1)
				)
			)
		)
	)
	(symbol
		(lib_id "antmicroTestPoints:TP_0.75mm_SMD")
		(at 196.85 208.28 0)
		(mirror y)
		(unit 1)
		(exclude_from_sim no)
		(in_bom no)
		(on_board yes)
		(dnp no)
		(property "Reference" "TP134"
			(at 186.69 208.28 0)
			(effects
				(font
					(size 1.27 1.27)
				)
				(justify right)
			)
		)
		(property "Value" "TP_0.75mm_SMD"
			(at 186.69 212.09 0)
			(effects
				(font
					(size 1.27 1.27)
					(thickness 0.15)
				)
				(justify left bottom)
				(hide yes)
			)
		)
		(property "Footprint" "antmicro-footprints:TP_SMD_0.75mm"
			(at 186.69 214.63 0)
			(effects
				(font
					(size 1.27 1.27)
					(thickness 0.15)
				)
				(justify left bottom)
				(hide yes)
			)
		)
		(property "Datasheet" ""
			(at 179.07 220.98 0)
			(effects
				(font
					(size 1.27 1.27)
					(thickness 0.15)
				)
				(justify left bottom)
				(hide yes)
			)
		)
		(property "Description" "SMT test point"
			(at 196.85 208.28 0)
			(effects
				(font
					(size 1.27 1.27)
				)
				(hide yes)
			)
		)
		(property "MPN" ""
			(at 186.055 219.71 0)
			(effects
				(font
					(size 1.27 1.27)
					(thickness 0.15)
				)
				(justify left bottom)
				(hide yes)
			)
		)
		(property "Manufacturer" ""
			(at 186.055 214.63 0)
			(effects
				(font
					(size 1.27 1.27)
					(thickness 0.15)
				)
				(justify left bottom)
				(hide yes)
			)
		)
		(property "Author" "Antmicro"
			(at 186.69 217.17 0)
			(effects
				(font
					(size 1.27 1.27)
					(thickness 0.15)
				)
				(justify left bottom)
				(hide yes)
			)
		)
		(property "License" "Apache-2.0"
			(at 186.69 219.71 0)
			(effects
				(font
					(size 1.27 1.27)
					(thickness 0.15)
				)
				(justify left bottom)
				(hide yes)
			)
		)
		(pin "1"
		)
		(instances
			(project "jetson-agx-thor-baseboard"
				(path ""
					(reference "TP134")
					(unit 1)
				)
			)
		)
	)
	(symbol
		(lib_id "antmicropower:+1V8")
		(at 368.3 207.01 0)
		(unit 1)
		(exclude_from_sim no)
		(in_bom yes)
		(on_board yes)
		(dnp no)
		(property "Reference" "#PWR080"
			(at 383.54 209.55 0)
			(effects
				(font
					(size 1.27 1.27)
					(thickness 0.15)
				)
				(justify left bottom)
				(hide yes)
			)
		)
		(property "Value" "+1V15"
			(at 368.3 203.2 0)
			(effects
				(font
					(size 1.27 1.27)
					(thickness 0.15)
				)
			)
		)
		(property "Footprint" ""
			(at 383.54 214.63 0)
			(effects
				(font
					(size 1.27 1.27)
					(thickness 0.15)
				)
				(justify left bottom)
				(hide yes)
			)
		)
		(property "Datasheet" ""
			(at 383.54 217.17 0)
			(effects
				(font
					(size 1.27 1.27)
					(thickness 0.15)
				)
				(justify left bottom)
				(hide yes)
			)
		)
		(property "Description" ""
			(at 368.3 207.01 0)
			(effects
				(font
					(size 1.27 1.27)
				)
				(hide yes)
			)
		)
		(property "Author" "Antmicro"
			(at 383.54 212.09 0)
			(effects
				(font
					(size 1.27 1.27)
					(thickness 0.15)
				)
				(justify left bottom)
				(hide yes)
			)
		)
		(property "License" "Apache-2.0"
			(at 383.54 214.63 0)
			(effects
				(font
					(size 1.27 1.27)
					(thickness 0.15)
				)
				(justify left bottom)
				(hide yes)
			)
		)
		(pin "1"
		)
		(instances
			(project "jetson-agx-thor-baseboard"
				(path ""
					(reference "#PWR080")
					(unit 1)
				)
			)
		)
	)
	(symbol
		(lib_id "antmicroLEDIndicationDiscrete:LED_G_0603_LTST-C190GKT")
		(at 377.19 201.93 90)
		(unit 1)
		(exclude_from_sim no)
		(in_bom yes)
		(on_board yes)
		(dnp no)
		(property "Reference" "D40"
			(at 378.46 198.12 90)
			(effects
				(font
					(size 1.27 1.27)
				)
				(justify right)
			)
		)
		(property "Value" "LED_G_0603_LTST-C190GKT"
			(at 384.81 179.07 0)
			(effects
				(font
					(size 1.27 1.27)
					(thickness 0.15)
				)
				(justify left bottom)
				(hide yes)
			)
		)
		(property "Footprint" "antmicro-footprints:LED_0603_1608Metric_G"
			(at 387.35 179.07 0)
			(effects
				(font
					(size 1.27 1.27)
					(thickness 0.15)
				)
				(justify left bottom)
				(hide yes)
			)
		)
		(property "Datasheet" "https://media.digikey.com/pdf/Data%20Sheets/Lite-On%20PDFs/LTST-C190GKT.pdf"
			(at 389.89 179.07 0)
			(effects
				(font
					(size 1.27 1.27)
					(thickness 0.15)
				)
				(justify left bottom)
				(hide yes)
			)
		)
		(property "Description" "LED, Green, SMD, 0603, 20 mA, 2.1 V, 569 nm"
			(at 377.19 201.93 0)
			(effects
				(font
					(size 1.27 1.27)
				)
				(hide yes)
			)
		)
		(property "MPN" "LTST-C190GKT"
			(at 392.43 179.07 0)
			(effects
				(font
					(size 1.27 1.27)
					(thickness 0.15)
				)
				(justify left bottom)
				(hide yes)
			)
		)
		(property "Manufacturer" "Lite-On"
			(at 394.97 179.07 0)
			(effects
				(font
					(size 1.27 1.27)
					(thickness 0.15)
				)
				(justify left bottom)
				(hide yes)
			)
		)
		(property "Author" "Antmicro"
			(at 397.51 179.07 0)
			(effects
				(font
					(size 1.27 1.27)
					(thickness 0.15)
				)
				(justify left bottom)
				(hide yes)
			)
		)
		(property "License" "Apache-2.0"
			(at 400.05 179.07 0)
			(effects
				(font
					(size 1.27 1.27)
					(thickness 0.15)
				)
				(justify left bottom)
				(hide yes)
			)
		)
		(property "Color" "Green"
			(at 378.46 200.66 90)
			(effects
				(font
					(size 1.27 1.27)
				)
				(justify right)
			)
		)
		(pin "1"
		)
		(pin "2"
		)
		(instances
			(project "jetson-agx-thor-baseboard"
				(path ""
					(reference "D40")
					(unit 1)
				)
			)
		)
	)
	(symbol
		(lib_id "antmicropower:+5V")
		(at 377.19 189.23 0)
		(unit 1)
		(exclude_from_sim no)
		(in_bom yes)
		(on_board yes)
		(dnp no)
		(property "Reference" "#PWR0167"
			(at 377.19 193.04 0)
			(effects
				(font
					(size 1.27 1.27)
				)
				(justify left bottom)
				(hide yes)
			)
		)
		(property "Value" "+5V"
			(at 377.19 185.42 0)
			(effects
				(font
					(size 1.27 1.27)
					(thickness 0.15)
				)
			)
		)
		(property "Footprint" ""
			(at 392.43 196.85 0)
			(effects
				(font
					(size 1.27 1.27)
					(thickness 0.15)
				)
				(justify left bottom)
				(hide yes)
			)
		)
		(property "Datasheet" ""
			(at 392.43 199.39 0)
			(effects
				(font
					(size 1.27 1.27)
					(thickness 0.15)
				)
				(justify left bottom)
				(hide yes)
			)
		)
		(property "Description" ""
			(at 377.19 189.23 0)
			(effects
				(font
					(size 1.27 1.27)
				)
				(hide yes)
			)
		)
		(property "Author" "Antmicro"
			(at 392.43 196.85 0)
			(effects
				(font
					(size 1.27 1.27)
					(thickness 0.15)
				)
				(justify left bottom)
				(hide yes)
			)
		)
		(property "License" "Apache-2.0"
			(at 392.43 199.39 0)
			(effects
				(font
					(size 1.27 1.27)
					(thickness 0.15)
				)
				(justify left bottom)
				(hide yes)
			)
		)
		(pin "1"
		)
		(instances
			(project "jetson-agx-thor-baseboard"
				(path ""
					(reference "#PWR0167")
					(unit 1)
				)
			)
		)
	)
	(symbol
		(lib_id "antmicroResistors0402:R_2k2_0402")
		(at 218.44 209.55 90)
		(unit 1)
		(exclude_from_sim no)
		(in_bom yes)
		(on_board yes)
		(dnp no)
		(fields_autoplaced yes)
		(property "Reference" "R51"
			(at 220.98 205.74 90)
			(effects
				(font
					(size 1.27 1.27)
					(thickness 0.15)
				)
				(justify right)
			)
		)
		(property "Value" "R_2k2_0402"
			(at 231.14 189.23 0)
			(effects
				(font
					(size 1.27 1.27)
					(thickness 0.15)
				)
				(justify left bottom)
				(hide yes)
			)
		)
		(property "Footprint" "antmicro-footprints:R_0402_1005Metric"
			(at 233.68 189.23 0)
			(effects
				(font
					(size 1.27 1.27)
					(thickness 0.15)
				)
				(justify left bottom)
				(hide yes)
			)
		)
		(property "Datasheet" "https://www.bourns.com/docs/product-datasheets/cr.pdf"
			(at 236.22 189.23 0)
			(effects
				(font
					(size 1.27 1.27)
					(thickness 0.15)
				)
				(justify left bottom)
				(hide yes)
			)
		)
		(property "Description" "SMD Chip Resistor, 2.2 kohm, ± 1%, 62.5 mW, 0402 [1005 Metric], Thick Film, General Purpose"
			(at 218.44 209.55 0)
			(effects
				(font
					(size 1.27 1.27)
				)
				(hide yes)
			)
		)
		(property "MPN" "CR0402-FX-2201GLF"
			(at 238.76 189.23 0)
			(effects
				(font
					(size 1.27 1.27)
					(thickness 0.15)
				)
				(justify left bottom)
				(hide yes)
			)
		)
		(property "Manufacturer" "Bourns"
			(at 241.3 189.23 0)
			(effects
				(font
					(size 1.27 1.27)
					(thickness 0.15)
				)
				(justify left bottom)
				(hide yes)
			)
		)
		(property "License" "Apache-2.0"
			(at 243.84 189.23 0)
			(effects
				(font
					(size 1.27 1.27)
					(thickness 0.15)
				)
				(justify left bottom)
				(hide yes)
			)
		)
		(property "Author" "Antmicro"
			(at 246.38 189.23 0)
			(effects
				(font
					(size 1.27 1.27)
					(thickness 0.15)
				)
				(justify left bottom)
				(hide yes)
			)
		)
		(property "Val" "2k2"
			(at 220.98 208.28 90)
			(effects
				(font
					(size 1.27 1.27)
					(thickness 0.15)
				)
				(justify right)
			)
		)
		(property "Tolerance" "1%"
			(at 228.6 189.23 0)
			(effects
				(font
					(size 1.27 1.27)
				)
				(justify left bottom)
				(hide yes)
			)
		)
		(pin "2"
		)
		(pin "1"
		)
		(instances
			(project "jetson-agx-thor-baseboard"
				(path ""
					(reference "R51")
					(unit 1)
				)
			)
		)
	)
	(symbol
		(lib_id "antmicropower:GND")
		(at 356.87 80.01 0)
		(unit 1)
		(exclude_from_sim no)
		(in_bom yes)
		(on_board yes)
		(dnp no)
		(property "Reference" "#PWR0611"
			(at 356.87 86.36 0)
			(effects
				(font
					(size 1.27 1.27)
				)
				(justify left bottom)
				(hide yes)
			)
		)
		(property "Value" "GND"
			(at 356.87 83.82 0)
			(effects
				(font
					(size 1.27 1.27)
					(thickness 0.15)
				)
			)
		)
		(property "Footprint" ""
			(at 365.76 87.63 0)
			(effects
				(font
					(size 1.27 1.27)
					(thickness 0.15)
				)
				(justify left bottom)
				(hide yes)
			)
		)
		(property "Datasheet" ""
			(at 365.76 92.71 0)
			(effects
				(font
					(size 1.27 1.27)
					(thickness 0.15)
				)
				(justify left bottom)
				(hide yes)
			)
		)
		(property "Description" ""
			(at 356.87 80.01 0)
			(effects
				(font
					(size 1.27 1.27)
				)
				(hide yes)
			)
		)
		(property "Author" "Antmicro"
			(at 365.76 87.63 0)
			(effects
				(font
					(size 1.27 1.27)
					(thickness 0.15)
				)
				(justify left bottom)
				(hide yes)
			)
		)
		(property "License" "Apache-2.0"
			(at 365.76 90.17 0)
			(effects
				(font
					(size 1.27 1.27)
					(thickness 0.15)
				)
				(justify left bottom)
				(hide yes)
			)
		)
		(pin "1"
		)
		(instances
			(project "jetson-agx-thor-baseboard"
				(path ""
					(reference "#PWR0611")
					(unit 1)
				)
			)
		)
	)
	(symbol
		(lib_id "antmicropower:GND")
		(at 383.54 116.84 0)
		(unit 1)
		(exclude_from_sim no)
		(in_bom yes)
		(on_board yes)
		(dnp no)
		(property "Reference" "#PWR0614"
			(at 383.54 123.19 0)
			(effects
				(font
					(size 1.27 1.27)
				)
				(justify left bottom)
				(hide yes)
			)
		)
		(property "Value" "GND"
			(at 383.54 120.65 0)
			(effects
				(font
					(size 1.27 1.27)
					(thickness 0.15)
				)
			)
		)
		(property "Footprint" ""
			(at 392.43 124.46 0)
			(effects
				(font
					(size 1.27 1.27)
					(thickness 0.15)
				)
				(justify left bottom)
				(hide yes)
			)
		)
		(property "Datasheet" ""
			(at 392.43 129.54 0)
			(effects
				(font
					(size 1.27 1.27)
					(thickness 0.15)
				)
				(justify left bottom)
				(hide yes)
			)
		)
		(property "Description" ""
			(at 383.54 116.84 0)
			(effects
				(font
					(size 1.27 1.27)
				)
				(hide yes)
			)
		)
		(property "Author" "Antmicro"
			(at 392.43 124.46 0)
			(effects
				(font
					(size 1.27 1.27)
					(thickness 0.15)
				)
				(justify left bottom)
				(hide yes)
			)
		)
		(property "License" "Apache-2.0"
			(at 392.43 127 0)
			(effects
				(font
					(size 1.27 1.27)
					(thickness 0.15)
				)
				(justify left bottom)
				(hide yes)
			)
		)
		(pin "1"
		)
		(instances
			(project "jetson-agx-thor-baseboard"
				(path ""
					(reference "#PWR0614")
					(unit 1)
				)
			)
		)
	)
	(symbol
		(lib_id "antmicropower:PWR_FLAG")
		(at 316.23 35.56 0)
		(unit 1)
		(exclude_from_sim no)
		(in_bom yes)
		(on_board yes)
		(dnp no)
		(property "Reference" "#FLG02"
			(at 316.23 33.655 0)
			(effects
				(font
					(size 1.27 1.27)
				)
				(hide yes)
			)
		)
		(property "Value" "PWR_FLAG"
			(at 316.23 27.94 90)
			(effects
				(font
					(size 1.27 1.27)
				)
			)
		)
		(property "Footprint" ""
			(at 316.23 35.56 0)
			(effects
				(font
					(size 1.27 1.27)
				)
				(hide yes)
			)
		)
		(property "Datasheet" ""
			(at 316.23 35.56 0)
			(effects
				(font
					(size 1.27 1.27)
				)
				(hide yes)
			)
		)
		(property "Description" ""
			(at 316.23 35.56 0)
			(effects
				(font
					(size 1.27 1.27)
				)
				(hide yes)
			)
		)
		(pin "1"
		)
		(instances
			(project "jetson-agx-thor-baseboard"
				(path ""
					(reference "#FLG02")
					(unit 1)
				)
			)
		)
	)
	(symbol
		(lib_id "antmicroResistors0402:R_10k_0402")
		(at 336.55 217.17 90)
		(unit 1)
		(exclude_from_sim no)
		(in_bom yes)
		(on_board yes)
		(dnp no)
		(property "Reference" "R84"
			(at 330.2 213.106 90)
			(effects
				(font
					(size 1.27 1.27)
				)
				(justify right)
			)
		)
		(property "Value" "R_10k_0402"
			(at 349.25 196.85 0)
			(effects
				(font
					(size 1.27 1.27)
					(thickness 0.15)
				)
				(justify left bottom)
				(hide yes)
			)
		)
		(property "Footprint" "antmicro-footprints:R_0402_1005Metric"
			(at 351.79 196.85 0)
			(effects
				(font
					(size 1.27 1.27)
					(thickness 0.15)
				)
				(justify left bottom)
				(hide yes)
			)
		)
		(property "Datasheet" "https://www.bourns.com/docs/product-datasheets/cr.pdf"
			(at 354.33 196.85 0)
			(effects
				(font
					(size 1.27 1.27)
					(thickness 0.15)
				)
				(justify left bottom)
				(hide yes)
			)
		)
		(property "Description" "SMD Chip Resistor, 10 kohm, ± 1%, 62.5 mW, 0402 [1005 Metric], Thick Film, General Purpose"
			(at 336.55 217.17 0)
			(effects
				(font
					(size 1.27 1.27)
				)
				(hide yes)
			)
		)
		(property "Manufacturer" "Bourns"
			(at 359.41 196.85 0)
			(effects
				(font
					(size 1.27 1.27)
					(thickness 0.15)
				)
				(justify left bottom)
				(hide yes)
			)
		)
		(property "MPN" "CR0402-FX-1002GLF"
			(at 356.87 196.85 0)
			(effects
				(font
					(size 1.27 1.27)
					(thickness 0.15)
				)
				(justify left bottom)
				(hide yes)
			)
		)
		(property "Val" "10k"
			(at 330.2 215.646 90)
			(effects
				(font
					(size 1.27 1.27)
					(thickness 0.15)
				)
				(justify right)
			)
		)
		(property "License" "Apache-2.0"
			(at 361.95 196.85 0)
			(effects
				(font
					(size 1.27 1.27)
					(thickness 0.15)
				)
				(justify left bottom)
				(hide yes)
			)
		)
		(property "Author" "Antmicro"
			(at 364.49 196.85 0)
			(effects
				(font
					(size 1.27 1.27)
					(thickness 0.15)
				)
				(justify left bottom)
				(hide yes)
			)
		)
		(property "Tolerance" "1%"
			(at 346.71 196.85 0)
			(effects
				(font
					(size 1.27 1.27)
				)
				(justify left bottom)
				(hide yes)
			)
		)
		(pin "1"
		)
		(pin "2"
		)
		(instances
			(project "jetson-agx-thor-baseboard"
				(path ""
					(reference "R84")
					(unit 1)
				)
			)
		)
	)
	(symbol
		(lib_id "antmicroLEDIndicationDiscrete:LED_G_0603_LTST-C190GKT")
		(at 218.44 215.9 90)
		(unit 1)
		(exclude_from_sim no)
		(in_bom yes)
		(on_board yes)
		(dnp no)
		(property "Reference" "D10"
			(at 219.71 212.09 90)
			(effects
				(font
					(size 1.27 1.27)
				)
				(justify right)
			)
		)
		(property "Value" "LED_G_0603_LTST-C190GKT"
			(at 226.06 193.04 0)
			(effects
				(font
					(size 1.27 1.27)
					(thickness 0.15)
				)
				(justify left bottom)
				(hide yes)
			)
		)
		(property "Footprint" "antmicro-footprints:LED_0603_1608Metric_G"
			(at 228.6 193.04 0)
			(effects
				(font
					(size 1.27 1.27)
					(thickness 0.15)
				)
				(justify left bottom)
				(hide yes)
			)
		)
		(property "Datasheet" "https://media.digikey.com/pdf/Data%20Sheets/Lite-On%20PDFs/LTST-C190GKT.pdf"
			(at 231.14 193.04 0)
			(effects
				(font
					(size 1.27 1.27)
					(thickness 0.15)
				)
				(justify left bottom)
				(hide yes)
			)
		)
		(property "Description" "LED, Green, SMD, 0603, 20 mA, 2.1 V, 569 nm"
			(at 218.44 215.9 0)
			(effects
				(font
					(size 1.27 1.27)
				)
				(hide yes)
			)
		)
		(property "MPN" "LTST-C190GKT"
			(at 233.68 193.04 0)
			(effects
				(font
					(size 1.27 1.27)
					(thickness 0.15)
				)
				(justify left bottom)
				(hide yes)
			)
		)
		(property "Manufacturer" "Lite-On"
			(at 236.22 193.04 0)
			(effects
				(font
					(size 1.27 1.27)
					(thickness 0.15)
				)
				(justify left bottom)
				(hide yes)
			)
		)
		(property "Author" "Antmicro"
			(at 238.76 193.04 0)
			(effects
				(font
					(size 1.27 1.27)
					(thickness 0.15)
				)
				(justify left bottom)
				(hide yes)
			)
		)
		(property "License" "Apache-2.0"
			(at 241.3 193.04 0)
			(effects
				(font
					(size 1.27 1.27)
					(thickness 0.15)
				)
				(justify left bottom)
				(hide yes)
			)
		)
		(property "Color" "Green"
			(at 219.71 214.63 90)
			(effects
				(font
					(size 1.27 1.27)
				)
				(justify right)
			)
		)
		(pin "1"
		)
		(pin "2"
		)
		(instances
			(project "jetson-agx-thor-baseboard"
				(path ""
					(reference "D10")
					(unit 1)
				)
			)
		)
	)
	(symbol
		(lib_id "antmicroLEDIndicationDiscrete:LED_G_0603_LTST-C190GKT")
		(at 279.4 215.9 90)
		(unit 1)
		(exclude_from_sim no)
		(in_bom yes)
		(on_board yes)
		(dnp no)
		(property "Reference" "D42"
			(at 280.67 212.09 90)
			(effects
				(font
					(size 1.27 1.27)
				)
				(justify right)
			)
		)
		(property "Value" "LED_G_0603_LTST-C190GKT"
			(at 287.02 193.04 0)
			(effects
				(font
					(size 1.27 1.27)
					(thickness 0.15)
				)
				(justify left bottom)
				(hide yes)
			)
		)
		(property "Footprint" "antmicro-footprints:LED_0603_1608Metric_G"
			(at 289.56 193.04 0)
			(effects
				(font
					(size 1.27 1.27)
					(thickness 0.15)
				)
				(justify left bottom)
				(hide yes)
			)
		)
		(property "Datasheet" "https://media.digikey.com/pdf/Data%20Sheets/Lite-On%20PDFs/LTST-C190GKT.pdf"
			(at 292.1 193.04 0)
			(effects
				(font
					(size 1.27 1.27)
					(thickness 0.15)
				)
				(justify left bottom)
				(hide yes)
			)
		)
		(property "Description" "LED, Green, SMD, 0603, 20 mA, 2.1 V, 569 nm"
			(at 279.4 215.9 0)
			(effects
				(font
					(size 1.27 1.27)
				)
				(hide yes)
			)
		)
		(property "MPN" "LTST-C190GKT"
			(at 294.64 193.04 0)
			(effects
				(font
					(size 1.27 1.27)
					(thickness 0.15)
				)
				(justify left bottom)
				(hide yes)
			)
		)
		(property "Manufacturer" "Lite-On"
			(at 297.18 193.04 0)
			(effects
				(font
					(size 1.27 1.27)
					(thickness 0.15)
				)
				(justify left bottom)
				(hide yes)
			)
		)
		(property "Author" "Antmicro"
			(at 299.72 193.04 0)
			(effects
				(font
					(size 1.27 1.27)
					(thickness 0.15)
				)
				(justify left bottom)
				(hide yes)
			)
		)
		(property "License" "Apache-2.0"
			(at 302.26 193.04 0)
			(effects
				(font
					(size 1.27 1.27)
					(thickness 0.15)
				)
				(justify left bottom)
				(hide yes)
			)
		)
		(property "Color" "Green"
			(at 280.67 214.63 90)
			(effects
				(font
					(size 1.27 1.27)
				)
				(justify right)
			)
		)
		(pin "1"
		)
		(pin "2"
		)
		(instances
			(project "jetson-agx-thor-baseboard"
				(path ""
					(reference "D42")
					(unit 1)
				)
			)
		)
	)
	(symbol
		(lib_id "antmicroTestPoints:TP_0.75mm_SMD")
		(at 317.5 190.5 0)
		(unit 1)
		(exclude_from_sim no)
		(in_bom no)
		(on_board yes)
		(dnp no)
		(property "Reference" "TP4"
			(at 321.818 190.5 0)
			(effects
				(font
					(size 1.27 1.27)
				)
				(justify left)
			)
		)
		(property "Value" "TP_0.75mm_SMD"
			(at 327.66 194.31 0)
			(effects
				(font
					(size 1.27 1.27)
					(thickness 0.15)
				)
				(justify left bottom)
				(hide yes)
			)
		)
		(property "Footprint" "antmicro-footprints:TP_SMD_0.75mm"
			(at 327.66 196.85 0)
			(effects
				(font
					(size 1.27 1.27)
					(thickness 0.15)
				)
				(justify left bottom)
				(hide yes)
			)
		)
		(property "Datasheet" ""
			(at 335.28 203.2 0)
			(effects
				(font
					(size 1.27 1.27)
					(thickness 0.15)
				)
				(justify left bottom)
				(hide yes)
			)
		)
		(property "Description" "SMT test point"
			(at 317.5 190.5 0)
			(effects
				(font
					(size 1.27 1.27)
				)
				(hide yes)
			)
		)
		(property "MPN" ""
			(at 328.295 201.93 0)
			(effects
				(font
					(size 1.27 1.27)
					(thickness 0.15)
				)
				(justify left bottom)
				(hide yes)
			)
		)
		(property "Manufacturer" ""
			(at 328.295 196.85 0)
			(effects
				(font
					(size 1.27 1.27)
					(thickness 0.15)
				)
				(justify left bottom)
				(hide yes)
			)
		)
		(property "Author" "Antmicro"
			(at 327.66 199.39 0)
			(effects
				(font
					(size 1.27 1.27)
					(thickness 0.15)
				)
				(justify left bottom)
				(hide yes)
			)
		)
		(property "License" "Apache-2.0"
			(at 327.66 201.93 0)
			(effects
				(font
					(size 1.27 1.27)
					(thickness 0.15)
				)
				(justify left bottom)
				(hide yes)
			)
		)
		(pin "1"
		)
		(instances
			(project "jetson-agx-thor-baseboard"
				(path ""
					(reference "TP4")
					(unit 1)
				)
			)
		)
	)
	(symbol
		(lib_id "antmicropower:GND")
		(at 200.66 217.17 0)
		(mirror y)
		(unit 1)
		(exclude_from_sim no)
		(in_bom yes)
		(on_board yes)
		(dnp no)
		(property "Reference" "#PWR034"
			(at 200.66 223.52 0)
			(effects
				(font
					(size 1.27 1.27)
				)
				(justify left bottom)
				(hide yes)
			)
		)
		(property "Value" "GND"
			(at 200.66 220.98 0)
			(effects
				(font
					(size 1.27 1.27)
					(thickness 0.15)
				)
			)
		)
		(property "Footprint" ""
			(at 191.77 224.79 0)
			(effects
				(font
					(size 1.27 1.27)
					(thickness 0.15)
				)
				(justify left bottom)
				(hide yes)
			)
		)
		(property "Datasheet" ""
			(at 191.77 229.87 0)
			(effects
				(font
					(size 1.27 1.27)
					(thickness 0.15)
				)
				(justify left bottom)
				(hide yes)
			)
		)
		(property "Description" ""
			(at 200.66 217.17 0)
			(effects
				(font
					(size 1.27 1.27)
				)
				(hide yes)
			)
		)
		(property "Author" "Antmicro"
			(at 191.77 224.79 0)
			(effects
				(font
					(size 1.27 1.27)
					(thickness 0.15)
				)
				(justify left bottom)
				(hide yes)
			)
		)
		(property "License" "Apache-2.0"
			(at 191.77 227.33 0)
			(effects
				(font
					(size 1.27 1.27)
					(thickness 0.15)
				)
				(justify left bottom)
				(hide yes)
			)
		)
		(pin "1"
		)
		(instances
			(project "jetson-agx-thor-baseboard"
				(path ""
					(reference "#PWR034")
					(unit 1)
				)
			)
		)
	)
	(symbol
		(lib_id "antmicropower:GND")
		(at 72.39 88.9 0)
		(mirror y)
		(unit 1)
		(exclude_from_sim no)
		(in_bom yes)
		(on_board yes)
		(dnp no)
		(property "Reference" "#PWR0662"
			(at 72.39 95.25 0)
			(effects
				(font
					(size 1.27 1.27)
				)
				(justify left bottom)
				(hide yes)
			)
		)
		(property "Value" "GND"
			(at 72.39 92.71 0)
			(effects
				(font
					(size 1.27 1.27)
					(thickness 0.15)
				)
			)
		)
		(property "Footprint" ""
			(at 63.5 96.52 0)
			(effects
				(font
					(size 1.27 1.27)
					(thickness 0.15)
				)
				(justify left bottom)
				(hide yes)
			)
		)
		(property "Datasheet" ""
			(at 63.5 101.6 0)
			(effects
				(font
					(size 1.27 1.27)
					(thickness 0.15)
				)
				(justify left bottom)
				(hide yes)
			)
		)
		(property "Description" ""
			(at 72.39 88.9 0)
			(effects
				(font
					(size 1.27 1.27)
				)
				(hide yes)
			)
		)
		(property "Author" "Antmicro"
			(at 63.5 96.52 0)
			(effects
				(font
					(size 1.27 1.27)
					(thickness 0.15)
				)
				(justify left bottom)
				(hide yes)
			)
		)
		(property "License" "Apache-2.0"
			(at 63.5 99.06 0)
			(effects
				(font
					(size 1.27 1.27)
					(thickness 0.15)
				)
				(justify left bottom)
				(hide yes)
			)
		)
		(pin "1"
		)
		(instances
			(project "jetson-agx-thor-baseboard"
				(path ""
					(reference "#PWR0662")
					(unit 1)
				)
			)
		)
	)
	(symbol
		(lib_id "antmicroTestPoints:TP_0.75mm_SMD")
		(at 287.02 85.09 90)
		(unit 1)
		(exclude_from_sim no)
		(in_bom no)
		(on_board yes)
		(dnp no)
		(property "Reference" "TP76"
			(at 284.734 79.756 90)
			(effects
				(font
					(size 1.27 1.27)
				)
				(justify right)
			)
		)
		(property "Value" "TP_0.75mm_SMD"
			(at 290.83 74.93 0)
			(effects
				(font
					(size 1.27 1.27)
					(thickness 0.15)
				)
				(justify left bottom)
				(hide yes)
			)
		)
		(property "Footprint" "antmicro-footprints:TP_SMD_0.75mm"
			(at 293.37 74.93 0)
			(effects
				(font
					(size 1.27 1.27)
					(thickness 0.15)
				)
				(justify left bottom)
				(hide yes)
			)
		)
		(property "Datasheet" ""
			(at 299.72 67.31 0)
			(effects
				(font
					(size 1.27 1.27)
					(thickness 0.15)
				)
				(justify left bottom)
				(hide yes)
			)
		)
		(property "Description" "SMT test point"
			(at 287.02 85.09 0)
			(effects
				(font
					(size 1.27 1.27)
				)
				(hide yes)
			)
		)
		(property "MPN" ""
			(at 298.45 74.295 0)
			(effects
				(font
					(size 1.27 1.27)
					(thickness 0.15)
				)
				(justify left bottom)
				(hide yes)
			)
		)
		(property "Manufacturer" ""
			(at 293.37 74.295 0)
			(effects
				(font
					(size 1.27 1.27)
					(thickness 0.15)
				)
				(justify left bottom)
				(hide yes)
			)
		)
		(property "Author" "Antmicro"
			(at 295.91 74.93 0)
			(effects
				(font
					(size 1.27 1.27)
					(thickness 0.15)
				)
				(justify left bottom)
				(hide yes)
			)
		)
		(property "License" "Apache-2.0"
			(at 298.45 74.93 0)
			(effects
				(font
					(size 1.27 1.27)
					(thickness 0.15)
				)
				(justify left bottom)
				(hide yes)
			)
		)
		(pin "1"
		)
		(instances
			(project "jetson-agx-thor-baseboard"
				(path ""
					(reference "TP76")
					(unit 1)
				)
			)
		)
	)
	(symbol
		(lib_id "antmicropower:GND")
		(at 300.99 217.17 0)
		(unit 1)
		(exclude_from_sim no)
		(in_bom yes)
		(on_board yes)
		(dnp no)
		(property "Reference" "#PWR070"
			(at 300.99 223.52 0)
			(effects
				(font
					(size 1.27 1.27)
				)
				(justify left bottom)
				(hide yes)
			)
		)
		(property "Value" "GND"
			(at 300.99 220.98 0)
			(effects
				(font
					(size 1.27 1.27)
					(thickness 0.15)
				)
			)
		)
		(property "Footprint" ""
			(at 309.88 224.79 0)
			(effects
				(font
					(size 1.27 1.27)
					(thickness 0.15)
				)
				(justify left bottom)
				(hide yes)
			)
		)
		(property "Datasheet" ""
			(at 309.88 229.87 0)
			(effects
				(font
					(size 1.27 1.27)
					(thickness 0.15)
				)
				(justify left bottom)
				(hide yes)
			)
		)
		(property "Description" ""
			(at 300.99 217.17 0)
			(effects
				(font
					(size 1.27 1.27)
				)
				(hide yes)
			)
		)
		(property "Author" "Antmicro"
			(at 309.88 224.79 0)
			(effects
				(font
					(size 1.27 1.27)
					(thickness 0.15)
				)
				(justify left bottom)
				(hide yes)
			)
		)
		(property "License" "Apache-2.0"
			(at 309.88 227.33 0)
			(effects
				(font
					(size 1.27 1.27)
					(thickness 0.15)
				)
				(justify left bottom)
				(hide yes)
			)
		)
		(pin "1"
		)
		(instances
			(project "jetson-agx-thor-baseboard"
				(path ""
					(reference "#PWR070")
					(unit 1)
				)
			)
		)
	)
	(symbol
		(lib_id "antmicroResistors0402:R_2k2_0402")
		(at 248.92 209.55 90)
		(unit 1)
		(exclude_from_sim no)
		(in_bom yes)
		(on_board yes)
		(dnp no)
		(fields_autoplaced yes)
		(property "Reference" "R412"
			(at 251.46 205.74 90)
			(effects
				(font
					(size 1.27 1.27)
					(thickness 0.15)
				)
				(justify right)
			)
		)
		(property "Value" "R_2k2_0402"
			(at 261.62 189.23 0)
			(effects
				(font
					(size 1.27 1.27)
					(thickness 0.15)
				)
				(justify left bottom)
				(hide yes)
			)
		)
		(property "Footprint" "antmicro-footprints:R_0402_1005Metric"
			(at 264.16 189.23 0)
			(effects
				(font
					(size 1.27 1.27)
					(thickness 0.15)
				)
				(justify left bottom)
				(hide yes)
			)
		)
		(property "Datasheet" "https://www.bourns.com/docs/product-datasheets/cr.pdf"
			(at 266.7 189.23 0)
			(effects
				(font
					(size 1.27 1.27)
					(thickness 0.15)
				)
				(justify left bottom)
				(hide yes)
			)
		)
		(property "Description" "SMD Chip Resistor, 2.2 kohm, ± 1%, 62.5 mW, 0402 [1005 Metric], Thick Film, General Purpose"
			(at 248.92 209.55 0)
			(effects
				(font
					(size 1.27 1.27)
				)
				(hide yes)
			)
		)
		(property "MPN" "CR0402-FX-2201GLF"
			(at 269.24 189.23 0)
			(effects
				(font
					(size 1.27 1.27)
					(thickness 0.15)
				)
				(justify left bottom)
				(hide yes)
			)
		)
		(property "Manufacturer" "Bourns"
			(at 271.78 189.23 0)
			(effects
				(font
					(size 1.27 1.27)
					(thickness 0.15)
				)
				(justify left bottom)
				(hide yes)
			)
		)
		(property "License" "Apache-2.0"
			(at 274.32 189.23 0)
			(effects
				(font
					(size 1.27 1.27)
					(thickness 0.15)
				)
				(justify left bottom)
				(hide yes)
			)
		)
		(property "Author" "Antmicro"
			(at 276.86 189.23 0)
			(effects
				(font
					(size 1.27 1.27)
					(thickness 0.15)
				)
				(justify left bottom)
				(hide yes)
			)
		)
		(property "Val" "2k2"
			(at 251.46 208.28 90)
			(effects
				(font
					(size 1.27 1.27)
					(thickness 0.15)
				)
				(justify right)
			)
		)
		(property "Tolerance" "1%"
			(at 259.08 189.23 0)
			(effects
				(font
					(size 1.27 1.27)
				)
				(justify left bottom)
				(hide yes)
			)
		)
		(pin "2"
		)
		(pin "1"
		)
		(instances
			(project "jetson-agx-thor-baseboard"
				(path ""
					(reference "R412")
					(unit 1)
				)
			)
		)
	)
	(symbol
		(lib_id "antmicropower:VCC")
		(at 259.08 181.61 0)
		(mirror y)
		(unit 1)
		(exclude_from_sim no)
		(in_bom yes)
		(on_board yes)
		(dnp no)
		(property "Reference" "#PWR0160"
			(at 259.08 185.42 0)
			(effects
				(font
					(size 1.27 1.27)
				)
				(hide yes)
			)
		)
		(property "Value" "+5V"
			(at 256.794 177.8 0)
			(effects
				(font
					(size 1.27 1.27)
				)
				(justify right)
			)
		)
		(property "Footprint" ""
			(at 259.08 181.61 0)
			(effects
				(font
					(size 1.27 1.27)
				)
				(hide yes)
			)
		)
		(property "Datasheet" ""
			(at 259.08 181.61 0)
			(effects
				(font
					(size 1.27 1.27)
				)
				(hide yes)
			)
		)
		(property "Description" ""
			(at 259.08 181.61 0)
			(effects
				(font
					(size 1.27 1.27)
				)
				(hide yes)
			)
		)
		(pin "1"
		)
		(instances
			(project "jetson-agx-thor-baseboard"
				(path ""
					(reference "#PWR0160")
					(unit 1)
				)
			)
		)
	)
	(symbol
		(lib_id "antmicropower:GND")
		(at 345.44 218.44 0)
		(unit 1)
		(exclude_from_sim no)
		(in_bom yes)
		(on_board yes)
		(dnp no)
		(property "Reference" "#PWR0514"
			(at 345.44 224.79 0)
			(effects
				(font
					(size 1.27 1.27)
				)
				(justify left bottom)
				(hide yes)
			)
		)
		(property "Value" "GND"
			(at 345.44 222.25 0)
			(effects
				(font
					(size 1.27 1.27)
					(thickness 0.15)
				)
			)
		)
		(property "Footprint" ""
			(at 354.33 226.06 0)
			(effects
				(font
					(size 1.27 1.27)
					(thickness 0.15)
				)
				(justify left bottom)
				(hide yes)
			)
		)
		(property "Datasheet" ""
			(at 354.33 231.14 0)
			(effects
				(font
					(size 1.27 1.27)
					(thickness 0.15)
				)
				(justify left bottom)
				(hide yes)
			)
		)
		(property "Description" ""
			(at 345.44 218.44 0)
			(effects
				(font
					(size 1.27 1.27)
				)
				(hide yes)
			)
		)
		(property "Author" "Antmicro"
			(at 354.33 226.06 0)
			(effects
				(font
					(size 1.27 1.27)
					(thickness 0.15)
				)
				(justify left bottom)
				(hide yes)
			)
		)
		(property "License" "Apache-2.0"
			(at 354.33 228.6 0)
			(effects
				(font
					(size 1.27 1.27)
					(thickness 0.15)
				)
				(justify left bottom)
				(hide yes)
			)
		)
		(pin "1"
		)
		(instances
			(project "jetson-agx-thor-baseboard"
				(path ""
					(reference "#PWR0514")
					(unit 1)
				)
			)
		)
	)
	(symbol
		(lib_id "antmicroTransistorsFETsMOSFETsSingle:SISS05DN-T1-GE3")
		(at 378.46 100.33 90)
		(unit 1)
		(exclude_from_sim no)
		(in_bom yes)
		(on_board yes)
		(dnp no)
		(fields_autoplaced yes)
		(property "Reference" "Q25"
			(at 375.92 87.63 90)
			(effects
				(font
					(size 1.27 1.27)
					(thickness 0.15)
				)
			)
		)
		(property "Value" "SISS05DN-T1-GE3"
			(at 388.62 85.09 0)
			(effects
				(font
					(size 1.27 1.27)
					(thickness 0.15)
				)
				(justify left bottom)
				(hide yes)
			)
		)
		(property "Footprint" "antmicro-footprints:Vishay_PowerPAK_1212-8_Single"
			(at 391.16 85.09 0)
			(effects
				(font
					(size 1.27 1.27)
					(thickness 0.15)
				)
				(justify left bottom)
				(hide yes)
			)
		)
		(property "Datasheet" "https://www.vishay.com/docs/77029/siss05dn.pdf"
			(at 393.7 85.09 0)
			(effects
				(font
					(size 1.27 1.27)
					(thickness 0.15)
				)
				(justify left bottom)
				(hide yes)
			)
		)
		(property "Description" "Power MOSFET, P Channel, 30 V, 108 A, 0.0035 ohm, PowerPAK 1212, Surface Mount"
			(at 396.24 85.09 0)
			(effects
				(font
					(size 1.27 1.27)
					(thickness 0.15)
				)
				(justify left bottom)
				(hide yes)
			)
		)
		(property "MPN" "SISS05DN-T1-GE3"
			(at 375.92 90.17 90)
			(effects
				(font
					(size 1.27 1.27)
					(thickness 0.15)
				)
			)
		)
		(property "Manufacturer" "Vishay"
			(at 398.78 85.09 0)
			(effects
				(font
					(size 1.27 1.27)
					(thickness 0.15)
				)
				(justify left bottom)
				(hide yes)
			)
		)
		(property "Author" "Antmicro"
			(at 401.32 85.09 0)
			(effects
				(font
					(size 1.27 1.27)
					(thickness 0.15)
				)
				(justify left bottom)
				(hide yes)
			)
		)
		(property "License" "Apache-2.0"
			(at 403.86 85.09 0)
			(effects
				(font
					(size 1.27 1.27)
					(thickness 0.15)
				)
				(justify left bottom)
				(hide yes)
			)
		)
		(pin "1"
		)
		(pin "4"
		)
		(pin "3"
		)
		(pin "5"
		)
		(pin "2"
		)
		(instances
			(project "jetson-agx-thor-baseboard"
				(path ""
					(reference "Q25")
					(unit 1)
				)
			)
		)
	)
	(symbol
		(lib_id "antmicropower:GND")
		(at 377.19 218.44 0)
		(unit 1)
		(exclude_from_sim no)
		(in_bom yes)
		(on_board yes)
		(dnp no)
		(property "Reference" "#PWR0170"
			(at 377.19 224.79 0)
			(effects
				(font
					(size 1.27 1.27)
				)
				(justify left bottom)
				(hide yes)
			)
		)
		(property "Value" "GND"
			(at 377.19 222.25 0)
			(effects
				(font
					(size 1.27 1.27)
					(thickness 0.15)
				)
			)
		)
		(property "Footprint" ""
			(at 386.08 226.06 0)
			(effects
				(font
					(size 1.27 1.27)
					(thickness 0.15)
				)
				(justify left bottom)
				(hide yes)
			)
		)
		(property "Datasheet" ""
			(at 386.08 231.14 0)
			(effects
				(font
					(size 1.27 1.27)
					(thickness 0.15)
				)
				(justify left bottom)
				(hide yes)
			)
		)
		(property "Description" ""
			(at 377.19 218.44 0)
			(effects
				(font
					(size 1.27 1.27)
				)
				(hide yes)
			)
		)
		(property "Author" "Antmicro"
			(at 386.08 226.06 0)
			(effects
				(font
					(size 1.27 1.27)
					(thickness 0.15)
				)
				(justify left bottom)
				(hide yes)
			)
		)
		(property "License" "Apache-2.0"
			(at 386.08 228.6 0)
			(effects
				(font
					(size 1.27 1.27)
					(thickness 0.15)
				)
				(justify left bottom)
				(hide yes)
			)
		)
		(pin "1"
		)
		(instances
			(project "jetson-agx-thor-baseboard"
				(path ""
					(reference "#PWR0170")
					(unit 1)
				)
			)
		)
	)
	(symbol
		(lib_id "antmicropower:GND")
		(at 193.04 43.18 0)
		(mirror y)
		(unit 1)
		(exclude_from_sim no)
		(in_bom yes)
		(on_board yes)
		(dnp no)
		(property "Reference" "#PWR079"
			(at 193.04 49.53 0)
			(effects
				(font
					(size 1.27 1.27)
				)
				(justify left bottom)
				(hide yes)
			)
		)
		(property "Value" "GND"
			(at 193.04 46.99 0)
			(effects
				(font
					(size 1.27 1.27)
					(thickness 0.15)
				)
			)
		)
		(property "Footprint" ""
			(at 184.15 50.8 0)
			(effects
				(font
					(size 1.27 1.27)
					(thickness 0.15)
				)
				(justify left bottom)
				(hide yes)
			)
		)
		(property "Datasheet" ""
			(at 184.15 55.88 0)
			(effects
				(font
					(size 1.27 1.27)
					(thickness 0.15)
				)
				(justify left bottom)
				(hide yes)
			)
		)
		(property "Description" ""
			(at 193.04 43.18 0)
			(effects
				(font
					(size 1.27 1.27)
				)
				(hide yes)
			)
		)
		(property "Author" "Antmicro"
			(at 184.15 50.8 0)
			(effects
				(font
					(size 1.27 1.27)
					(thickness 0.15)
				)
				(justify left bottom)
				(hide yes)
			)
		)
		(property "License" "Apache-2.0"
			(at 184.15 53.34 0)
			(effects
				(font
					(size 1.27 1.27)
					(thickness 0.15)
				)
				(justify left bottom)
				(hide yes)
			)
		)
		(pin "1"
		)
		(instances
			(project "jetson-agx-thor-baseboard"
				(path ""
					(reference "#PWR079")
					(unit 1)
				)
			)
		)
	)
	(symbol
		(lib_id "antmicropower:PWR_FLAG")
		(at 276.86 83.82 0)
		(unit 1)
		(exclude_from_sim no)
		(in_bom yes)
		(on_board yes)
		(dnp no)
		(property "Reference" "#FLG08"
			(at 276.86 81.915 0)
			(effects
				(font
					(size 1.27 1.27)
				)
				(hide yes)
			)
		)
		(property "Value" "PWR_FLAG"
			(at 276.86 80.01 0)
			(effects
				(font
					(size 1.27 1.27)
				)
			)
		)
		(property "Footprint" ""
			(at 276.86 83.82 0)
			(effects
				(font
					(size 1.27 1.27)
				)
				(hide yes)
			)
		)
		(property "Datasheet" ""
			(at 276.86 83.82 0)
			(effects
				(font
					(size 1.27 1.27)
				)
				(hide yes)
			)
		)
		(property "Description" ""
			(at 276.86 83.82 0)
			(effects
				(font
					(size 1.27 1.27)
				)
				(hide yes)
			)
		)
		(pin "1"
		)
		(instances
			(project "jetson-agx-thor-baseboard"
				(path ""
					(reference "#FLG08")
					(unit 1)
				)
			)
		)
	)
	(symbol
		(lib_id "antmicroTestPoints:TP_0.75mm_SMD")
		(at 288.29 121.92 90)
		(unit 1)
		(exclude_from_sim no)
		(in_bom no)
		(on_board yes)
		(dnp no)
		(property "Reference" "TP77"
			(at 286.004 116.586 90)
			(effects
				(font
					(size 1.27 1.27)
				)
				(justify right)
			)
		)
		(property "Value" "TP_0.75mm_SMD"
			(at 292.1 111.76 0)
			(effects
				(font
					(size 1.27 1.27)
					(thickness 0.15)
				)
				(justify left bottom)
				(hide yes)
			)
		)
		(property "Footprint" "antmicro-footprints:TP_SMD_0.75mm"
			(at 294.64 111.76 0)
			(effects
				(font
					(size 1.27 1.27)
					(thickness 0.15)
				)
				(justify left bottom)
				(hide yes)
			)
		)
		(property "Datasheet" ""
			(at 300.99 104.14 0)
			(effects
				(font
					(size 1.27 1.27)
					(thickness 0.15)
				)
				(justify left bottom)
				(hide yes)
			)
		)
		(property "Description" "SMT test point"
			(at 288.29 121.92 0)
			(effects
				(font
					(size 1.27 1.27)
				)
				(hide yes)
			)
		)
		(property "MPN" ""
			(at 299.72 111.125 0)
			(effects
				(font
					(size 1.27 1.27)
					(thickness 0.15)
				)
				(justify left bottom)
				(hide yes)
			)
		)
		(property "Manufacturer" ""
			(at 294.64 111.125 0)
			(effects
				(font
					(size 1.27 1.27)
					(thickness 0.15)
				)
				(justify left bottom)
				(hide yes)
			)
		)
		(property "Author" "Antmicro"
			(at 297.18 111.76 0)
			(effects
				(font
					(size 1.27 1.27)
					(thickness 0.15)
				)
				(justify left bottom)
				(hide yes)
			)
		)
		(property "License" "Apache-2.0"
			(at 299.72 111.76 0)
			(effects
				(font
					(size 1.27 1.27)
					(thickness 0.15)
				)
				(justify left bottom)
				(hide yes)
			)
		)
		(pin "1"
		)
		(instances
			(project "jetson-agx-thor-baseboard"
				(path ""
					(reference "TP77")
					(unit 1)
				)
			)
		)
	)
	(symbol
		(lib_id "antmicropower:VCC")
		(at 218.44 181.61 0)
		(mirror y)
		(unit 1)
		(exclude_from_sim no)
		(in_bom yes)
		(on_board yes)
		(dnp no)
		(property "Reference" "#PWR095"
			(at 218.44 185.42 0)
			(effects
				(font
					(size 1.27 1.27)
				)
				(hide yes)
			)
		)
		(property "Value" "SYS_VIN_HV"
			(at 212.598 177.8 0)
			(effects
				(font
					(size 1.27 1.27)
				)
				(justify right)
			)
		)
		(property "Footprint" ""
			(at 218.44 181.61 0)
			(effects
				(font
					(size 1.27 1.27)
				)
				(hide yes)
			)
		)
		(property "Datasheet" ""
			(at 218.44 181.61 0)
			(effects
				(font
					(size 1.27 1.27)
				)
				(hide yes)
			)
		)
		(property "Description" ""
			(at 218.44 181.61 0)
			(effects
				(font
					(size 1.27 1.27)
				)
				(hide yes)
			)
		)
		(pin "1"
		)
		(instances
			(project "jetson-agx-thor-baseboard"
				(path ""
					(reference "#PWR095")
					(unit 1)
				)
			)
		)
	)
	(symbol
		(lib_id "antmicropower:+5V")
		(at 279.4 181.61 0)
		(unit 1)
		(exclude_from_sim no)
		(in_bom yes)
		(on_board yes)
		(dnp no)
		(property "Reference" "#PWR0108"
			(at 279.4 185.42 0)
			(effects
				(font
					(size 1.27 1.27)
				)
				(justify left bottom)
				(hide yes)
			)
		)
		(property "Value" "+5V_AON"
			(at 279.4 177.8 0)
			(effects
				(font
					(size 1.27 1.27)
					(thickness 0.15)
				)
			)
		)
		(property "Footprint" ""
			(at 294.64 189.23 0)
			(effects
				(font
					(size 1.27 1.27)
					(thickness 0.15)
				)
				(justify left bottom)
				(hide yes)
			)
		)
		(property "Datasheet" ""
			(at 294.64 191.77 0)
			(effects
				(font
					(size 1.27 1.27)
					(thickness 0.15)
				)
				(justify left bottom)
				(hide yes)
			)
		)
		(property "Description" ""
			(at 279.4 181.61 0)
			(effects
				(font
					(size 1.27 1.27)
				)
				(hide yes)
			)
		)
		(property "Author" "Antmicro"
			(at 294.64 189.23 0)
			(effects
				(font
					(size 1.27 1.27)
					(thickness 0.15)
				)
				(justify left bottom)
				(hide yes)
			)
		)
		(property "License" "Apache-2.0"
			(at 294.64 191.77 0)
			(effects
				(font
					(size 1.27 1.27)
					(thickness 0.15)
				)
				(justify left bottom)
				(hide yes)
			)
		)
		(pin "1"
		)
		(instances
			(project "jetson-agx-thor-baseboard"
				(path ""
					(reference "#PWR0108")
					(unit 1)
				)
			)
		)
	)
	(symbol
		(lib_id "antmicropower:VCC")
		(at 269.24 181.61 0)
		(mirror y)
		(unit 1)
		(exclude_from_sim no)
		(in_bom yes)
		(on_board yes)
		(dnp no)
		(property "Reference" "#PWR0452"
			(at 269.24 185.42 0)
			(effects
				(font
					(size 1.27 1.27)
				)
				(hide yes)
			)
		)
		(property "Value" "+5V_SOM"
			(at 264.16 177.8 0)
			(effects
				(font
					(size 1.27 1.27)
				)
				(justify right)
			)
		)
		(property "Footprint" ""
			(at 269.24 181.61 0)
			(effects
				(font
					(size 1.27 1.27)
				)
				(hide yes)
			)
		)
		(property "Datasheet" ""
			(at 269.24 181.61 0)
			(effects
				(font
					(size 1.27 1.27)
				)
				(hide yes)
			)
		)
		(property "Description" ""
			(at 269.24 181.61 0)
			(effects
				(font
					(size 1.27 1.27)
				)
				(hide yes)
			)
		)
		(pin "1"
		)
		(instances
			(project "jetson-agx-thor-baseboard"
				(path ""
					(reference "#PWR0452")
					(unit 1)
				)
			)
		)
	)
	(symbol
		(lib_id "antmicroTVSDiodes:PTVS26VS1UR,115")
		(at 219.71 36.83 270)
		(unit 1)
		(exclude_from_sim no)
		(in_bom yes)
		(on_board yes)
		(dnp no)
		(property "Reference" "D2"
			(at 220.98 38.1 90)
			(effects
				(font
					(size 1.27 1.27)
				)
				(justify left)
			)
		)
		(property "Value" "PTVS26VS1UR,115"
			(at 204.47 58.42 0)
			(effects
				(font
					(size 1.27 1.27)
					(thickness 0.15)
				)
				(justify left bottom)
				(hide yes)
			)
		)
		(property "Footprint" "antmicro-footprints:D_SOD-123"
			(at 212.09 58.42 0)
			(effects
				(font
					(size 1.27 1.27)
					(thickness 0.15)
				)
				(justify left bottom)
				(hide yes)
			)
		)
		(property "Datasheet" "https://www.mouser.com/datasheet/2/916/PTVSXS1UR_SER-1545507.pdf"
			(at 209.55 58.42 0)
			(effects
				(font
					(size 1.27 1.27)
					(thickness 0.15)
				)
				(justify left bottom)
				(hide yes)
			)
		)
		(property "Description" "Unidirectional TVS, 8 kV,  SOD-123F, 26 V, 400 W"
			(at 219.71 36.83 0)
			(effects
				(font
					(size 1.27 1.27)
				)
				(hide yes)
			)
		)
		(property "Manufacturer" "Nexperia"
			(at 207.01 58.42 0)
			(effects
				(font
					(size 1.27 1.27)
					(thickness 0.15)
				)
				(justify left bottom)
				(hide yes)
			)
		)
		(property "MPN" "PTVS26VS1UR,115"
			(at 220.98 40.64 90)
			(effects
				(font
					(size 1.27 1.27)
					(thickness 0.15)
				)
				(justify left)
			)
		)
		(property "Author" "Antmicro"
			(at 201.93 58.42 0)
			(effects
				(font
					(size 1.27 1.27)
					(thickness 0.15)
				)
				(justify left bottom)
				(hide yes)
			)
		)
		(property "License" "Apache-2.0"
			(at 199.39 58.42 0)
			(effects
				(font
					(size 1.27 1.27)
					(thickness 0.15)
				)
				(justify left bottom)
				(hide yes)
			)
		)
		(pin "1"
		)
		(pin "2"
		)
		(instances
			(project "jetson-agx-thor-baseboard"
				(path ""
					(reference "D2")
					(unit 1)
				)
			)
		)
	)
	(symbol
		(lib_id "antmicroTestPoints:TP_0.75mm_SMD")
		(at 317.5 182.88 0)
		(unit 1)
		(exclude_from_sim no)
		(in_bom no)
		(on_board yes)
		(dnp no)
		(property "Reference" "TP98"
			(at 321.818 182.88 0)
			(effects
				(font
					(size 1.27 1.27)
				)
				(justify left)
			)
		)
		(property "Value" "TP_0.75mm_SMD"
			(at 327.66 186.69 0)
			(effects
				(font
					(size 1.27 1.27)
					(thickness 0.15)
				)
				(justify left bottom)
				(hide yes)
			)
		)
		(property "Footprint" "antmicro-footprints:TP_SMD_0.75mm"
			(at 327.66 189.23 0)
			(effects
				(font
					(size 1.27 1.27)
					(thickness 0.15)
				)
				(justify left bottom)
				(hide yes)
			)
		)
		(property "Datasheet" ""
			(at 335.28 195.58 0)
			(effects
				(font
					(size 1.27 1.27)
					(thickness 0.15)
				)
				(justify left bottom)
				(hide yes)
			)
		)
		(property "Description" "SMT test point"
			(at 317.5 182.88 0)
			(effects
				(font
					(size 1.27 1.27)
				)
				(hide yes)
			)
		)
		(property "MPN" ""
			(at 328.295 194.31 0)
			(effects
				(font
					(size 1.27 1.27)
					(thickness 0.15)
				)
				(justify left bottom)
				(hide yes)
			)
		)
		(property "Manufacturer" ""
			(at 328.295 189.23 0)
			(effects
				(font
					(size 1.27 1.27)
					(thickness 0.15)
				)
				(justify left bottom)
				(hide yes)
			)
		)
		(property "Author" "Antmicro"
			(at 327.66 191.77 0)
			(effects
				(font
					(size 1.27 1.27)
					(thickness 0.15)
				)
				(justify left bottom)
				(hide yes)
			)
		)
		(property "License" "Apache-2.0"
			(at 327.66 194.31 0)
			(effects
				(font
					(size 1.27 1.27)
					(thickness 0.15)
				)
				(justify left bottom)
				(hide yes)
			)
		)
		(pin "1"
		)
		(instances
			(project "jetson-agx-thor-baseboard"
				(path ""
					(reference "TP98")
					(unit 1)
				)
			)
		)
	)
	(symbol
		(lib_id "antmicropower:GND")
		(at 336.55 218.44 0)
		(unit 1)
		(exclude_from_sim no)
		(in_bom yes)
		(on_board yes)
		(dnp no)
		(property "Reference" "#PWR0516"
			(at 336.55 224.79 0)
			(effects
				(font
					(size 1.27 1.27)
				)
				(justify left bottom)
				(hide yes)
			)
		)
		(property "Value" "GND"
			(at 336.55 222.25 0)
			(effects
				(font
					(size 1.27 1.27)
					(thickness 0.15)
				)
			)
		)
		(property "Footprint" ""
			(at 345.44 226.06 0)
			(effects
				(font
					(size 1.27 1.27)
					(thickness 0.15)
				)
				(justify left bottom)
				(hide yes)
			)
		)
		(property "Datasheet" ""
			(at 345.44 231.14 0)
			(effects
				(font
					(size 1.27 1.27)
					(thickness 0.15)
				)
				(justify left bottom)
				(hide yes)
			)
		)
		(property "Description" ""
			(at 336.55 218.44 0)
			(effects
				(font
					(size 1.27 1.27)
				)
				(hide yes)
			)
		)
		(property "Author" "Antmicro"
			(at 345.44 226.06 0)
			(effects
				(font
					(size 1.27 1.27)
					(thickness 0.15)
				)
				(justify left bottom)
				(hide yes)
			)
		)
		(property "License" "Apache-2.0"
			(at 345.44 228.6 0)
			(effects
				(font
					(size 1.27 1.27)
					(thickness 0.15)
				)
				(justify left bottom)
				(hide yes)
			)
		)
		(pin "1"
		)
		(instances
			(project "jetson-agx-thor-baseboard"
				(path ""
					(reference "#PWR0516")
					(unit 1)
				)
			)
		)
	)
	(symbol
		(lib_id "antmicroTestPoints:TP_0.75mm_SMD")
		(at 196.85 185.42 180)
		(unit 1)
		(exclude_from_sim no)
		(in_bom no)
		(on_board yes)
		(dnp no)
		(property "Reference" "TP126"
			(at 186.69 185.42 0)
			(effects
				(font
					(size 1.27 1.27)
				)
				(justify right)
			)
		)
		(property "Value" "TP_0.75mm_SMD"
			(at 186.69 181.61 0)
			(effects
				(font
					(size 1.27 1.27)
					(thickness 0.15)
				)
				(justify left bottom)
				(hide yes)
			)
		)
		(property "Footprint" "antmicro-footprints:TP_SMD_0.75mm"
			(at 186.69 179.07 0)
			(effects
				(font
					(size 1.27 1.27)
					(thickness 0.15)
				)
				(justify left bottom)
				(hide yes)
			)
		)
		(property "Datasheet" ""
			(at 179.07 172.72 0)
			(effects
				(font
					(size 1.27 1.27)
					(thickness 0.15)
				)
				(justify left bottom)
				(hide yes)
			)
		)
		(property "Description" "SMT test point"
			(at 196.85 185.42 0)
			(effects
				(font
					(size 1.27 1.27)
				)
				(hide yes)
			)
		)
		(property "MPN" ""
			(at 186.055 173.99 0)
			(effects
				(font
					(size 1.27 1.27)
					(thickness 0.15)
				)
				(justify left bottom)
				(hide yes)
			)
		)
		(property "Manufacturer" ""
			(at 186.055 179.07 0)
			(effects
				(font
					(size 1.27 1.27)
					(thickness 0.15)
				)
				(justify left bottom)
				(hide yes)
			)
		)
		(property "Author" "Antmicro"
			(at 186.69 176.53 0)
			(effects
				(font
					(size 1.27 1.27)
					(thickness 0.15)
				)
				(justify left bottom)
				(hide yes)
			)
		)
		(property "License" "Apache-2.0"
			(at 186.69 173.99 0)
			(effects
				(font
					(size 1.27 1.27)
					(thickness 0.15)
				)
				(justify left bottom)
				(hide yes)
			)
		)
		(pin "1"
		)
		(instances
			(project "jetson-agx-thor-baseboard"
				(path ""
					(reference "TP126")
					(unit 1)
				)
			)
		)
	)
	(symbol
		(lib_id "antmicroLEDIndicationDiscrete:LED_G_0603_LTST-C190GKT")
		(at 300.99 215.9 90)
		(unit 1)
		(exclude_from_sim no)
		(in_bom yes)
		(on_board yes)
		(dnp no)
		(property "Reference" "D3"
			(at 302.26 212.09 90)
			(effects
				(font
					(size 1.27 1.27)
				)
				(justify right)
			)
		)
		(property "Value" "LED_G_0603_LTST-C190GKT"
			(at 308.61 193.04 0)
			(effects
				(font
					(size 1.27 1.27)
					(thickness 0.15)
				)
				(justify left bottom)
				(hide yes)
			)
		)
		(property "Footprint" "antmicro-footprints:LED_0603_1608Metric_G"
			(at 311.15 193.04 0)
			(effects
				(font
					(size 1.27 1.27)
					(thickness 0.15)
				)
				(justify left bottom)
				(hide yes)
			)
		)
		(property "Datasheet" "https://media.digikey.com/pdf/Data%20Sheets/Lite-On%20PDFs/LTST-C190GKT.pdf"
			(at 313.69 193.04 0)
			(effects
				(font
					(size 1.27 1.27)
					(thickness 0.15)
				)
				(justify left bottom)
				(hide yes)
			)
		)
		(property "Description" "LED, Green, SMD, 0603, 20 mA, 2.1 V, 569 nm"
			(at 300.99 215.9 0)
			(effects
				(font
					(size 1.27 1.27)
				)
				(hide yes)
			)
		)
		(property "MPN" "LTST-C190GKT"
			(at 316.23 193.04 0)
			(effects
				(font
					(size 1.27 1.27)
					(thickness 0.15)
				)
				(justify left bottom)
				(hide yes)
			)
		)
		(property "Manufacturer" "Lite-On"
			(at 318.77 193.04 0)
			(effects
				(font
					(size 1.27 1.27)
					(thickness 0.15)
				)
				(justify left bottom)
				(hide yes)
			)
		)
		(property "Author" "Antmicro"
			(at 321.31 193.04 0)
			(effects
				(font
					(size 1.27 1.27)
					(thickness 0.15)
				)
				(justify left bottom)
				(hide yes)
			)
		)
		(property "License" "Apache-2.0"
			(at 323.85 193.04 0)
			(effects
				(font
					(size 1.27 1.27)
					(thickness 0.15)
				)
				(justify left bottom)
				(hide yes)
			)
		)
		(property "Color" "Green"
			(at 302.26 214.63 90)
			(effects
				(font
					(size 1.27 1.27)
				)
				(justify right)
			)
		)
		(pin "1"
		)
		(pin "2"
		)
		(instances
			(project "jetson-agx-thor-baseboard"
				(path ""
					(reference "D3")
					(unit 1)
				)
			)
		)
	)
	(symbol
		(lib_id "antmicroPMICVoltageRegulatorsLinear:LD39100PUR")
		(at 74.93 81.28 0)
		(unit 1)
		(exclude_from_sim no)
		(in_bom yes)
		(on_board yes)
		(dnp no)
		(fields_autoplaced yes)
		(property "Reference" "U79"
			(at 82.55 74.295 0)
			(effects
				(font
					(size 1.27 1.27)
					(thickness 0.15)
				)
			)
		)
		(property "Value" "LD39100PUR"
			(at 105.41 88.9 0)
			(effects
				(font
					(size 1.27 1.27)
					(thickness 0.15)
				)
				(justify left bottom)
				(hide yes)
			)
		)
		(property "Footprint" "antmicro-footprints:DFN-6-1EP_3x3mm_P1mm_EP1.5x2.4mm"
			(at 105.41 91.44 0)
			(effects
				(font
					(size 1.27 1.27)
					(thickness 0.15)
				)
				(justify left bottom)
				(hide yes)
			)
		)
		(property "Datasheet" "https://eu.mouser.com/datasheet/2/389/ld39100-1849679.pdf"
			(at 105.41 93.98 0)
			(effects
				(font
					(size 1.27 1.27)
					(thickness 0.15)
				)
				(justify left bottom)
				(hide yes)
			)
		)
		(property "Description" "LDO Voltage Regulator 1A Low Quiescent Reg 1.5 to 5.5 V 200mV"
			(at 105.41 104.14 0)
			(effects
				(font
					(size 1.27 1.27)
				)
				(justify left bottom)
				(hide yes)
			)
		)
		(property "MPN" "LD39100PUR"
			(at 82.55 76.835 0)
			(effects
				(font
					(size 1.27 1.27)
					(thickness 0.15)
				)
			)
		)
		(property "Manufacturer" "STMicroelectronics"
			(at 105.41 96.52 0)
			(effects
				(font
					(size 1.27 1.27)
					(thickness 0.15)
				)
				(justify left bottom)
				(hide yes)
			)
		)
		(property "Author" "Antmicro"
			(at 105.41 99.06 0)
			(effects
				(font
					(size 1.27 1.27)
					(thickness 0.15)
				)
				(justify left bottom)
				(hide yes)
			)
		)
		(property "License" "Apache-2.0"
			(at 105.41 101.6 0)
			(effects
				(font
					(size 1.27 1.27)
					(thickness 0.15)
				)
				(justify left bottom)
				(hide yes)
			)
		)
		(pin "5"
		)
		(pin "4"
		)
		(pin "6"
		)
		(pin "1"
		)
		(pin "3"
		)
		(pin "2"
		)
		(pin "7"
		)
		(instances
			(project ""
				(path ""
					(reference "U79")
					(unit 1)
				)
			)
		)
	)
	(symbol
		(lib_id "antmicroLEDIndicationDiscrete:LED_G_0603_LTST-C190GKT")
		(at 290.83 215.9 90)
		(unit 1)
		(exclude_from_sim no)
		(in_bom yes)
		(on_board yes)
		(dnp no)
		(property "Reference" "D31"
			(at 292.1 212.09 90)
			(effects
				(font
					(size 1.27 1.27)
				)
				(justify right)
			)
		)
		(property "Value" "LED_G_0603_LTST-C190GKT"
			(at 298.45 193.04 0)
			(effects
				(font
					(size 1.27 1.27)
					(thickness 0.15)
				)
				(justify left bottom)
				(hide yes)
			)
		)
		(property "Footprint" "antmicro-footprints:LED_0603_1608Metric_G"
			(at 300.99 193.04 0)
			(effects
				(font
					(size 1.27 1.27)
					(thickness 0.15)
				)
				(justify left bottom)
				(hide yes)
			)
		)
		(property "Datasheet" "https://media.digikey.com/pdf/Data%20Sheets/Lite-On%20PDFs/LTST-C190GKT.pdf"
			(at 303.53 193.04 0)
			(effects
				(font
					(size 1.27 1.27)
					(thickness 0.15)
				)
				(justify left bottom)
				(hide yes)
			)
		)
		(property "Description" "LED, Green, SMD, 0603, 20 mA, 2.1 V, 569 nm"
			(at 290.83 215.9 0)
			(effects
				(font
					(size 1.27 1.27)
				)
				(hide yes)
			)
		)
		(property "MPN" "LTST-C190GKT"
			(at 306.07 193.04 0)
			(effects
				(font
					(size 1.27 1.27)
					(thickness 0.15)
				)
				(justify left bottom)
				(hide yes)
			)
		)
		(property "Manufacturer" "Lite-On"
			(at 308.61 193.04 0)
			(effects
				(font
					(size 1.27 1.27)
					(thickness 0.15)
				)
				(justify left bottom)
				(hide yes)
			)
		)
		(property "Author" "Antmicro"
			(at 311.15 193.04 0)
			(effects
				(font
					(size 1.27 1.27)
					(thickness 0.15)
				)
				(justify left bottom)
				(hide yes)
			)
		)
		(property "License" "Apache-2.0"
			(at 313.69 193.04 0)
			(effects
				(font
					(size 1.27 1.27)
					(thickness 0.15)
				)
				(justify left bottom)
				(hide yes)
			)
		)
		(property "Color" "Green"
			(at 292.1 214.63 90)
			(effects
				(font
					(size 1.27 1.27)
				)
				(justify right)
			)
		)
		(pin "1"
		)
		(pin "2"
		)
		(instances
			(project "jetson-agx-thor-baseboard"
				(path ""
					(reference "D31")
					(unit 1)
				)
			)
		)
	)
	(symbol
		(lib_id "antmicroTestPoints:TP_0.75mm_SMD")
		(at 196.85 182.88 180)
		(unit 1)
		(exclude_from_sim no)
		(in_bom no)
		(on_board yes)
		(dnp no)
		(property "Reference" "TP125"
			(at 186.69 182.88 0)
			(effects
				(font
					(size 1.27 1.27)
				)
				(justify right)
			)
		)
		(property "Value" "TP_0.75mm_SMD"
			(at 186.69 179.07 0)
			(effects
				(font
					(size 1.27 1.27)
					(thickness 0.15)
				)
				(justify left bottom)
				(hide yes)
			)
		)
		(property "Footprint" "antmicro-footprints:TP_SMD_0.75mm"
			(at 186.69 176.53 0)
			(effects
				(font
					(size 1.27 1.27)
					(thickness 0.15)
				)
				(justify left bottom)
				(hide yes)
			)
		)
		(property "Datasheet" ""
			(at 179.07 170.18 0)
			(effects
				(font
					(size 1.27 1.27)
					(thickness 0.15)
				)
				(justify left bottom)
				(hide yes)
			)
		)
		(property "Description" "SMT test point"
			(at 196.85 182.88 0)
			(effects
				(font
					(size 1.27 1.27)
				)
				(hide yes)
			)
		)
		(property "MPN" ""
			(at 186.055 171.45 0)
			(effects
				(font
					(size 1.27 1.27)
					(thickness 0.15)
				)
				(justify left bottom)
				(hide yes)
			)
		)
		(property "Manufacturer" ""
			(at 186.055 176.53 0)
			(effects
				(font
					(size 1.27 1.27)
					(thickness 0.15)
				)
				(justify left bottom)
				(hide yes)
			)
		)
		(property "Author" "Antmicro"
			(at 186.69 173.99 0)
			(effects
				(font
					(size 1.27 1.27)
					(thickness 0.15)
				)
				(justify left bottom)
				(hide yes)
			)
		)
		(property "License" "Apache-2.0"
			(at 186.69 171.45 0)
			(effects
				(font
					(size 1.27 1.27)
					(thickness 0.15)
				)
				(justify left bottom)
				(hide yes)
			)
		)
		(pin "1"
		)
		(instances
			(project "jetson-agx-thor-baseboard"
				(path ""
					(reference "TP125")
					(unit 1)
				)
			)
		)
	)
	(symbol
		(lib_id "antmicroTestPoints:TP_0.75mm_SMD")
		(at 196.85 203.2 180)
		(unit 1)
		(exclude_from_sim no)
		(in_bom no)
		(on_board yes)
		(dnp no)
		(property "Reference" "TP133"
			(at 186.69 203.2 0)
			(effects
				(font
					(size 1.27 1.27)
				)
				(justify right)
			)
		)
		(property "Value" "TP_0.75mm_SMD"
			(at 186.69 199.39 0)
			(effects
				(font
					(size 1.27 1.27)
					(thickness 0.15)
				)
				(justify left bottom)
				(hide yes)
			)
		)
		(property "Footprint" "antmicro-footprints:TP_SMD_0.75mm"
			(at 186.69 196.85 0)
			(effects
				(font
					(size 1.27 1.27)
					(thickness 0.15)
				)
				(justify left bottom)
				(hide yes)
			)
		)
		(property "Datasheet" ""
			(at 179.07 190.5 0)
			(effects
				(font
					(size 1.27 1.27)
					(thickness 0.15)
				)
				(justify left bottom)
				(hide yes)
			)
		)
		(property "Description" "SMT test point"
			(at 196.85 203.2 0)
			(effects
				(font
					(size 1.27 1.27)
				)
				(hide yes)
			)
		)
		(property "MPN" ""
			(at 186.055 191.77 0)
			(effects
				(font
					(size 1.27 1.27)
					(thickness 0.15)
				)
				(justify left bottom)
				(hide yes)
			)
		)
		(property "Manufacturer" ""
			(at 186.055 196.85 0)
			(effects
				(font
					(size 1.27 1.27)
					(thickness 0.15)
				)
				(justify left bottom)
				(hide yes)
			)
		)
		(property "Author" "Antmicro"
			(at 186.69 194.31 0)
			(effects
				(font
					(size 1.27 1.27)
					(thickness 0.15)
				)
				(justify left bottom)
				(hide yes)
			)
		)
		(property "License" "Apache-2.0"
			(at 186.69 191.77 0)
			(effects
				(font
					(size 1.27 1.27)
					(thickness 0.15)
				)
				(justify left bottom)
				(hide yes)
			)
		)
		(pin "1"
		)
		(instances
			(project "jetson-agx-thor-baseboard"
				(path ""
					(reference "TP133")
					(unit 1)
				)
			)
		)
	)
	(symbol
		(lib_id "antmicroTestPoints:TP_0.75mm_SMD")
		(at 317.5 208.28 0)
		(unit 1)
		(exclude_from_sim no)
		(in_bom no)
		(on_board yes)
		(dnp no)
		(property "Reference" "TP3"
			(at 325.12 208.28 0)
			(effects
				(font
					(size 1.27 1.27)
				)
				(justify right)
			)
		)
		(property "Value" "TP_0.75mm_SMD"
			(at 327.66 212.09 0)
			(effects
				(font
					(size 1.27 1.27)
					(thickness 0.15)
				)
				(justify left bottom)
				(hide yes)
			)
		)
		(property "Footprint" "antmicro-footprints:TP_SMD_0.75mm"
			(at 327.66 214.63 0)
			(effects
				(font
					(size 1.27 1.27)
					(thickness 0.15)
				)
				(justify left bottom)
				(hide yes)
			)
		)
		(property "Datasheet" ""
			(at 335.28 220.98 0)
			(effects
				(font
					(size 1.27 1.27)
					(thickness 0.15)
				)
				(justify left bottom)
				(hide yes)
			)
		)
		(property "Description" "SMT test point"
			(at 317.5 208.28 0)
			(effects
				(font
					(size 1.27 1.27)
				)
				(hide yes)
			)
		)
		(property "MPN" ""
			(at 328.295 219.71 0)
			(effects
				(font
					(size 1.27 1.27)
					(thickness 0.15)
				)
				(justify left bottom)
				(hide yes)
			)
		)
		(property "Manufacturer" ""
			(at 328.295 214.63 0)
			(effects
				(font
					(size 1.27 1.27)
					(thickness 0.15)
				)
				(justify left bottom)
				(hide yes)
			)
		)
		(property "Author" "Antmicro"
			(at 327.66 217.17 0)
			(effects
				(font
					(size 1.27 1.27)
					(thickness 0.15)
				)
				(justify left bottom)
				(hide yes)
			)
		)
		(property "License" "Apache-2.0"
			(at 327.66 219.71 0)
			(effects
				(font
					(size 1.27 1.27)
					(thickness 0.15)
				)
				(justify left bottom)
				(hide yes)
			)
		)
		(pin "1"
		)
		(instances
			(project "jetson-agx-thor-baseboard"
				(path ""
					(reference "TP3")
					(unit 1)
				)
			)
		)
	)
	(symbol
		(lib_id "antmicropower:GND")
		(at 228.6 217.17 0)
		(unit 1)
		(exclude_from_sim no)
		(in_bom yes)
		(on_board yes)
		(dnp no)
		(property "Reference" "#PWR0609"
			(at 228.6 223.52 0)
			(effects
				(font
					(size 1.27 1.27)
				)
				(justify left bottom)
				(hide yes)
			)
		)
		(property "Value" "GND"
			(at 228.6 220.98 0)
			(effects
				(font
					(size 1.27 1.27)
					(thickness 0.15)
				)
			)
		)
		(property "Footprint" ""
			(at 237.49 224.79 0)
			(effects
				(font
					(size 1.27 1.27)
					(thickness 0.15)
				)
				(justify left bottom)
				(hide yes)
			)
		)
		(property "Datasheet" ""
			(at 237.49 229.87 0)
			(effects
				(font
					(size 1.27 1.27)
					(thickness 0.15)
				)
				(justify left bottom)
				(hide yes)
			)
		)
		(property "Description" ""
			(at 228.6 217.17 0)
			(effects
				(font
					(size 1.27 1.27)
				)
				(hide yes)
			)
		)
		(property "Author" "Antmicro"
			(at 237.49 224.79 0)
			(effects
				(font
					(size 1.27 1.27)
					(thickness 0.15)
				)
				(justify left bottom)
				(hide yes)
			)
		)
		(property "License" "Apache-2.0"
			(at 237.49 227.33 0)
			(effects
				(font
					(size 1.27 1.27)
					(thickness 0.15)
				)
				(justify left bottom)
				(hide yes)
			)
		)
		(pin "1"
		)
		(instances
			(project "jetson-agx-thor-baseboard"
				(path ""
					(reference "#PWR0609")
					(unit 1)
				)
			)
		)
	)
	(symbol
		(lib_id "antmicroTestPoints:TP_0.75mm_SMD")
		(at 196.85 193.04 180)
		(unit 1)
		(exclude_from_sim no)
		(in_bom no)
		(on_board yes)
		(dnp no)
		(property "Reference" "TP129"
			(at 186.69 193.04 0)
			(effects
				(font
					(size 1.27 1.27)
				)
				(justify right)
			)
		)
		(property "Value" "TP_0.75mm_SMD"
			(at 186.69 189.23 0)
			(effects
				(font
					(size 1.27 1.27)
					(thickness 0.15)
				)
				(justify left bottom)
				(hide yes)
			)
		)
		(property "Footprint" "antmicro-footprints:TP_SMD_0.75mm"
			(at 186.69 186.69 0)
			(effects
				(font
					(size 1.27 1.27)
					(thickness 0.15)
				)
				(justify left bottom)
				(hide yes)
			)
		)
		(property "Datasheet" ""
			(at 179.07 180.34 0)
			(effects
				(font
					(size 1.27 1.27)
					(thickness 0.15)
				)
				(justify left bottom)
				(hide yes)
			)
		)
		(property "Description" "SMT test point"
			(at 196.85 193.04 0)
			(effects
				(font
					(size 1.27 1.27)
				)
				(hide yes)
			)
		)
		(property "MPN" ""
			(at 186.055 181.61 0)
			(effects
				(font
					(size 1.27 1.27)
					(thickness 0.15)
				)
				(justify left bottom)
				(hide yes)
			)
		)
		(property "Manufacturer" ""
			(at 186.055 186.69 0)
			(effects
				(font
					(size 1.27 1.27)
					(thickness 0.15)
				)
				(justify left bottom)
				(hide yes)
			)
		)
		(property "Author" "Antmicro"
			(at 186.69 184.15 0)
			(effects
				(font
					(size 1.27 1.27)
					(thickness 0.15)
				)
				(justify left bottom)
				(hide yes)
			)
		)
		(property "License" "Apache-2.0"
			(at 186.69 181.61 0)
			(effects
				(font
					(size 1.27 1.27)
					(thickness 0.15)
				)
				(justify left bottom)
				(hide yes)
			)
		)
		(pin "1"
		)
		(instances
			(project "jetson-agx-thor-baseboard"
				(path ""
					(reference "TP129")
					(unit 1)
				)
			)
		)
	)
	(symbol
		(lib_id "antmicroResistors0402:R_1k_0402")
		(at 208.28 209.55 90)
		(unit 1)
		(exclude_from_sim no)
		(in_bom yes)
		(on_board yes)
		(dnp no)
		(fields_autoplaced yes)
		(property "Reference" "R372"
			(at 210.82 205.74 90)
			(effects
				(font
					(size 1.27 1.27)
					(thickness 0.15)
				)
				(justify right)
			)
		)
		(property "Value" "R_1k_0402"
			(at 220.98 189.23 0)
			(effects
				(font
					(size 1.27 1.27)
					(thickness 0.15)
				)
				(justify left bottom)
				(hide yes)
			)
		)
		(property "Footprint" "antmicro-footprints:R_0402_1005Metric"
			(at 223.52 189.23 0)
			(effects
				(font
					(size 1.27 1.27)
					(thickness 0.15)
				)
				(justify left bottom)
				(hide yes)
			)
		)
		(property "Datasheet" "https://www.bourns.com/docs/product-datasheets/cr.pdf"
			(at 226.06 189.23 0)
			(effects
				(font
					(size 1.27 1.27)
					(thickness 0.15)
				)
				(justify left bottom)
				(hide yes)
			)
		)
		(property "Description" "SMD Chip Resistor, 1 kohm, ± 1%, 63 mW, 0402 [1005 Metric], Thick Film, General Purpose"
			(at 238.76 189.23 0)
			(effects
				(font
					(size 1.27 1.27)
				)
				(justify left bottom)
				(hide yes)
			)
		)
		(property "MPN" "CR0402-FX-1001GLF"
			(at 228.6 189.23 0)
			(effects
				(font
					(size 1.27 1.27)
					(thickness 0.15)
				)
				(justify left bottom)
				(hide yes)
			)
		)
		(property "Manufacturer" "Bourns"
			(at 231.14 189.23 0)
			(effects
				(font
					(size 1.27 1.27)
					(thickness 0.15)
				)
				(justify left bottom)
				(hide yes)
			)
		)
		(property "License" "Apache-2.0"
			(at 233.68 189.23 0)
			(effects
				(font
					(size 1.27 1.27)
					(thickness 0.15)
				)
				(justify left bottom)
				(hide yes)
			)
		)
		(property "Author" "Antmicro"
			(at 236.22 189.23 0)
			(effects
				(font
					(size 1.27 1.27)
					(thickness 0.15)
				)
				(justify left bottom)
				(hide yes)
			)
		)
		(property "Val" "1k"
			(at 210.82 208.28 90)
			(effects
				(font
					(size 1.27 1.27)
					(thickness 0.15)
				)
				(justify right)
			)
		)
		(property "Tolerance" "1%"
			(at 218.44 189.23 0)
			(effects
				(font
					(size 1.27 1.27)
				)
				(justify left bottom)
				(hide yes)
			)
		)
		(pin "2"
		)
		(pin "1"
		)
		(instances
			(project ""
				(path ""
					(reference "R372")
					(unit 1)
				)
			)
		)
	)
	(symbol
		(lib_id "antmicroOverUnderVoltageProtection:MAX16013")
		(at 266.7 57.15 0)
		(unit 1)
		(exclude_from_sim no)
		(in_bom yes)
		(on_board yes)
		(dnp no)
		(property "Reference" "U9"
			(at 268.986 54.356 0)
			(effects
				(font
					(size 1.27 1.27)
					(thickness 0.15)
				)
				(justify left bottom)
			)
		)
		(property "Value" "MAX16013"
			(at 302.26 64.77 0)
			(effects
				(font
					(size 1.27 1.27)
					(thickness 0.15)
				)
				(justify left bottom)
				(hide yes)
			)
		)
		(property "Footprint" "antmicro-footprints:TDFN-6-1EP_3x3mm_P0.95mm"
			(at 302.26 67.31 0)
			(effects
				(font
					(size 1.27 1.27)
					(thickness 0.15)
				)
				(justify left bottom)
				(hide yes)
			)
		)
		(property "Datasheet" "https://www.analog.com/media/en/technical-documentation/data-sheets/max16010-max16014.pdf"
			(at 302.26 69.85 0)
			(effects
				(font
					(size 1.27 1.27)
					(thickness 0.15)
				)
				(justify left bottom)
				(hide yes)
			)
		)
		(property "Description" "Over voltage, reverse voltage protection"
			(at 302.26 72.39 0)
			(effects
				(font
					(size 1.27 1.27)
					(thickness 0.15)
				)
				(justify left bottom)
				(hide yes)
			)
		)
		(property "Manufacturer" "Analog Devices"
			(at 302.26 74.93 0)
			(effects
				(font
					(size 1.27 1.27)
					(thickness 0.15)
				)
				(justify left bottom)
				(hide yes)
			)
		)
		(property "MPN" "MAX16013TT-T"
			(at 268.986 66.548 0)
			(effects
				(font
					(size 1.27 1.27)
					(thickness 0.15)
				)
				(justify left bottom)
			)
		)
		(property "Author" "Antmicro"
			(at 302.26 77.47 0)
			(effects
				(font
					(size 1.27 1.27)
					(thickness 0.15)
				)
				(justify left bottom)
				(hide yes)
			)
		)
		(property "License" "Apache-2.0"
			(at 302.26 80.01 0)
			(effects
				(font
					(size 1.27 1.27)
					(thickness 0.15)
				)
				(justify left bottom)
				(hide yes)
			)
		)
		(pin "2"
		)
		(pin "3"
		)
		(pin "5"
		)
		(pin "4"
		)
		(pin "6"
		)
		(pin "1"
		)
		(pin "7"
		)
		(instances
			(project ""
				(path ""
					(reference "U9")
					(unit 1)
				)
			)
		)
	)
	(symbol
		(lib_id "antmicropower:GND")
		(at 208.28 217.17 0)
		(unit 1)
		(exclude_from_sim no)
		(in_bom yes)
		(on_board yes)
		(dnp no)
		(property "Reference" "#PWR0182"
			(at 208.28 223.52 0)
			(effects
				(font
					(size 1.27 1.27)
				)
				(justify left bottom)
				(hide yes)
			)
		)
		(property "Value" "GND"
			(at 208.28 220.98 0)
			(effects
				(font
					(size 1.27 1.27)
					(thickness 0.15)
				)
			)
		)
		(property "Footprint" ""
			(at 217.17 224.79 0)
			(effects
				(font
					(size 1.27 1.27)
					(thickness 0.15)
				)
				(justify left bottom)
				(hide yes)
			)
		)
		(property "Datasheet" ""
			(at 217.17 229.87 0)
			(effects
				(font
					(size 1.27 1.27)
					(thickness 0.15)
				)
				(justify left bottom)
				(hide yes)
			)
		)
		(property "Description" ""
			(at 208.28 217.17 0)
			(effects
				(font
					(size 1.27 1.27)
				)
				(hide yes)
			)
		)
		(property "Author" "Antmicro"
			(at 217.17 224.79 0)
			(effects
				(font
					(size 1.27 1.27)
					(thickness 0.15)
				)
				(justify left bottom)
				(hide yes)
			)
		)
		(property "License" "Apache-2.0"
			(at 217.17 227.33 0)
			(effects
				(font
					(size 1.27 1.27)
					(thickness 0.15)
				)
				(justify left bottom)
				(hide yes)
			)
		)
		(pin "1"
		)
		(instances
			(project "jetson-agx-thor-baseboard"
				(path ""
					(reference "#PWR0182")
					(unit 1)
				)
			)
		)
	)
	(symbol
		(lib_id "antmicroPMICORControllersIdealDiodes:LTC4412IS6")
		(at 359.41 71.12 0)
		(unit 1)
		(exclude_from_sim no)
		(in_bom yes)
		(on_board yes)
		(dnp no)
		(fields_autoplaced yes)
		(property "Reference" "U63"
			(at 368.3 63.5 0)
			(effects
				(font
					(size 1.27 1.27)
					(thickness 0.15)
				)
			)
		)
		(property "Value" "LTC4412IS6"
			(at 391.16 76.2 0)
			(effects
				(font
					(size 1.27 1.27)
					(thickness 0.15)
				)
				(justify left bottom)
				(hide yes)
			)
		)
		(property "Footprint" "antmicro-footprints:SOT-23-6"
			(at 391.16 78.74 0)
			(effects
				(font
					(size 1.27 1.27)
					(thickness 0.15)
				)
				(justify left bottom)
				(hide yes)
			)
		)
		(property "Datasheet" "https://www.analog.com/media/en/technical-documentation/data-sheets/4412fb.pdf"
			(at 391.16 81.28 0)
			(effects
				(font
					(size 1.27 1.27)
					(thickness 0.15)
				)
				(justify left bottom)
				(hide yes)
			)
		)
		(property "Description" "Ideal diode controller"
			(at 359.41 71.12 0)
			(effects
				(font
					(size 1.27 1.27)
				)
				(hide yes)
			)
		)
		(property "MPN" "LTC4412IS6#TRMPBF"
			(at 368.3 66.04 0)
			(effects
				(font
					(size 1.27 1.27)
					(thickness 0.15)
				)
			)
		)
		(property "Manufacturer" "Analog Devices"
			(at 391.16 86.36 0)
			(effects
				(font
					(size 1.27 1.27)
					(thickness 0.15)
				)
				(justify left bottom)
				(hide yes)
			)
		)
		(property "Author" "Antmicro"
			(at 391.16 88.9 0)
			(effects
				(font
					(size 1.27 1.27)
					(thickness 0.15)
				)
				(justify left bottom)
				(hide yes)
			)
		)
		(property "License" "Apache-2.0"
			(at 391.16 91.44 0)
			(effects
				(font
					(size 1.27 1.27)
					(thickness 0.15)
				)
				(justify left bottom)
				(hide yes)
			)
		)
		(pin "3"
		)
		(pin "5"
		)
		(pin "4"
		)
		(pin "2"
		)
		(pin "1"
		)
		(pin "6"
		)
		(instances
			(project "jetson-agx-thor-baseboard"
				(path ""
					(reference "U63")
					(unit 1)
				)
			)
		)
	)
	(symbol
		(lib_id "antmicroTestPoints:TP_0.75mm_SMD")
		(at 317.5 187.96 0)
		(unit 1)
		(exclude_from_sim no)
		(in_bom no)
		(on_board yes)
		(dnp no)
		(property "Reference" "TP61"
			(at 321.818 187.96 0)
			(effects
				(font
					(size 1.27 1.27)
				)
				(justify left)
			)
		)
		(property "Value" "TP_0.75mm_SMD"
			(at 327.66 191.77 0)
			(effects
				(font
					(size 1.27 1.27)
					(thickness 0.15)
				)
				(justify left bottom)
				(hide yes)
			)
		)
		(property "Footprint" "antmicro-footprints:TP_SMD_0.75mm"
			(at 327.66 194.31 0)
			(effects
				(font
					(size 1.27 1.27)
					(thickness 0.15)
				)
				(justify left bottom)
				(hide yes)
			)
		)
		(property "Datasheet" ""
			(at 335.28 200.66 0)
			(effects
				(font
					(size 1.27 1.27)
					(thickness 0.15)
				)
				(justify left bottom)
				(hide yes)
			)
		)
		(property "Description" "SMT test point"
			(at 317.5 187.96 0)
			(effects
				(font
					(size 1.27 1.27)
				)
				(hide yes)
			)
		)
		(property "MPN" ""
			(at 328.295 199.39 0)
			(effects
				(font
					(size 1.27 1.27)
					(thickness 0.15)
				)
				(justify left bottom)
				(hide yes)
			)
		)
		(property "Manufacturer" ""
			(at 328.295 194.31 0)
			(effects
				(font
					(size 1.27 1.27)
					(thickness 0.15)
				)
				(justify left bottom)
				(hide yes)
			)
		)
		(property "Author" "Antmicro"
			(at 327.66 196.85 0)
			(effects
				(font
					(size 1.27 1.27)
					(thickness 0.15)
				)
				(justify left bottom)
				(hide yes)
			)
		)
		(property "License" "Apache-2.0"
			(at 327.66 199.39 0)
			(effects
				(font
					(size 1.27 1.27)
					(thickness 0.15)
				)
				(justify left bottom)
				(hide yes)
			)
		)
		(pin "1"
		)
		(instances
			(project "jetson-agx-thor-baseboard"
				(path ""
					(reference "TP61")
					(unit 1)
				)
			)
		)
	)
	(symbol
		(lib_id "antmicropower:GND")
		(at 60.96 88.9 0)
		(unit 1)
		(exclude_from_sim no)
		(in_bom yes)
		(on_board yes)
		(dnp no)
		(property "Reference" "#PWR0135"
			(at 60.96 95.25 0)
			(effects
				(font
					(size 1.27 1.27)
				)
				(justify left bottom)
				(hide yes)
			)
		)
		(property "Value" "GND"
			(at 60.96 92.71 0)
			(effects
				(font
					(size 1.27 1.27)
					(thickness 0.15)
				)
			)
		)
		(property "Footprint" ""
			(at 69.85 96.52 0)
			(effects
				(font
					(size 1.27 1.27)
					(thickness 0.15)
				)
				(justify left bottom)
				(hide yes)
			)
		)
		(property "Datasheet" ""
			(at 69.85 101.6 0)
			(effects
				(font
					(size 1.27 1.27)
					(thickness 0.15)
				)
				(justify left bottom)
				(hide yes)
			)
		)
		(property "Description" ""
			(at 60.96 88.9 0)
			(effects
				(font
					(size 1.27 1.27)
				)
				(hide yes)
			)
		)
		(property "Author" "Antmicro"
			(at 69.85 96.52 0)
			(effects
				(font
					(size 1.27 1.27)
					(thickness 0.15)
				)
				(justify left bottom)
				(hide yes)
			)
		)
		(property "License" "Apache-2.0"
			(at 69.85 99.06 0)
			(effects
				(font
					(size 1.27 1.27)
					(thickness 0.15)
				)
				(justify left bottom)
				(hide yes)
			)
		)
		(pin "1"
		)
		(instances
			(project "jetson-agx-thor-baseboard"
				(path ""
					(reference "#PWR0135")
					(unit 1)
				)
			)
		)
	)
	(symbol
		(lib_id "antmicroLEDIndicationDiscrete:LED_G_0603_LTST-C190GKT")
		(at 208.28 215.9 90)
		(unit 1)
		(exclude_from_sim no)
		(in_bom yes)
		(on_board yes)
		(dnp no)
		(property "Reference" "D63"
			(at 209.55 212.09 90)
			(effects
				(font
					(size 1.27 1.27)
				)
				(justify right)
			)
		)
		(property "Value" "LED_G_0603_LTST-C190GKT"
			(at 215.9 193.04 0)
			(effects
				(font
					(size 1.27 1.27)
					(thickness 0.15)
				)
				(justify left bottom)
				(hide yes)
			)
		)
		(property "Footprint" "antmicro-footprints:LED_0603_1608Metric_G"
			(at 218.44 193.04 0)
			(effects
				(font
					(size 1.27 1.27)
					(thickness 0.15)
				)
				(justify left bottom)
				(hide yes)
			)
		)
		(property "Datasheet" "https://media.digikey.com/pdf/Data%20Sheets/Lite-On%20PDFs/LTST-C190GKT.pdf"
			(at 220.98 193.04 0)
			(effects
				(font
					(size 1.27 1.27)
					(thickness 0.15)
				)
				(justify left bottom)
				(hide yes)
			)
		)
		(property "Description" "LED, Green, SMD, 0603, 20 mA, 2.1 V, 569 nm"
			(at 208.28 215.9 0)
			(effects
				(font
					(size 1.27 1.27)
				)
				(hide yes)
			)
		)
		(property "MPN" "LTST-C190GKT"
			(at 223.52 193.04 0)
			(effects
				(font
					(size 1.27 1.27)
					(thickness 0.15)
				)
				(justify left bottom)
				(hide yes)
			)
		)
		(property "Manufacturer" "Lite-On"
			(at 226.06 193.04 0)
			(effects
				(font
					(size 1.27 1.27)
					(thickness 0.15)
				)
				(justify left bottom)
				(hide yes)
			)
		)
		(property "Author" "Antmicro"
			(at 228.6 193.04 0)
			(effects
				(font
					(size 1.27 1.27)
					(thickness 0.15)
				)
				(justify left bottom)
				(hide yes)
			)
		)
		(property "License" "Apache-2.0"
			(at 231.14 193.04 0)
			(effects
				(font
					(size 1.27 1.27)
					(thickness 0.15)
				)
				(justify left bottom)
				(hide yes)
			)
		)
		(property "Color" "Green"
			(at 209.55 214.63 90)
			(effects
				(font
					(size 1.27 1.27)
				)
				(justify right)
			)
		)
		(pin "1"
		)
		(pin "2"
		)
		(instances
			(project "jetson-agx-thor-baseboard"
				(path ""
					(reference "D63")
					(unit 1)
				)
			)
		)
	)
	(symbol
		(lib_id "antmicropower:GND")
		(at 275.59 44.45 0)
		(unit 1)
		(exclude_from_sim no)
		(in_bom yes)
		(on_board yes)
		(dnp no)
		(property "Reference" "#PWR0661"
			(at 284.48 46.99 0)
			(effects
				(font
					(size 1.27 1.27)
					(thickness 0.15)
				)
				(justify left bottom)
				(hide yes)
			)
		)
		(property "Value" "GND"
			(at 275.59 48.26 0)
			(effects
				(font
					(size 1.27 1.27)
					(thickness 0.15)
				)
			)
		)
		(property "Footprint" ""
			(at 284.48 52.07 0)
			(effects
				(font
					(size 1.27 1.27)
					(thickness 0.15)
				)
				(justify left bottom)
				(hide yes)
			)
		)
		(property "Datasheet" ""
			(at 284.48 57.15 0)
			(effects
				(font
					(size 1.27 1.27)
					(thickness 0.15)
				)
				(justify left bottom)
				(hide yes)
			)
		)
		(property "Description" ""
			(at 284.48 59.69 0)
			(effects
				(font
					(size 1.27 1.27)
				)
				(justify left bottom)
				(hide yes)
			)
		)
		(property "Author" "Antmicro"
			(at 284.48 52.07 0)
			(effects
				(font
					(size 1.27 1.27)
					(thickness 0.15)
				)
				(justify left bottom)
				(hide yes)
			)
		)
		(property "License" "Apache-2.0"
			(at 284.48 54.61 0)
			(effects
				(font
					(size 1.27 1.27)
					(thickness 0.15)
				)
				(justify left bottom)
				(hide yes)
			)
		)
		(pin "1"
		)
		(instances
			(project "jetson-agx-thor-baseboard"
				(path ""
					(reference "#PWR0661")
					(unit 1)
				)
			)
		)
	)
	(symbol
		(lib_id "antmicropower:GND")
		(at 238.76 217.17 0)
		(unit 1)
		(exclude_from_sim no)
		(in_bom yes)
		(on_board yes)
		(dnp no)
		(property "Reference" "#PWR075"
			(at 238.76 223.52 0)
			(effects
				(font
					(size 1.27 1.27)
				)
				(justify left bottom)
				(hide yes)
			)
		)
		(property "Value" "GND"
			(at 238.76 220.98 0)
			(effects
				(font
					(size 1.27 1.27)
					(thickness 0.15)
				)
			)
		)
		(property "Footprint" ""
			(at 247.65 224.79 0)
			(effects
				(font
					(size 1.27 1.27)
					(thickness 0.15)
				)
				(justify left bottom)
				(hide yes)
			)
		)
		(property "Datasheet" ""
			(at 247.65 229.87 0)
			(effects
				(font
					(size 1.27 1.27)
					(thickness 0.15)
				)
				(justify left bottom)
				(hide yes)
			)
		)
		(property "Description" ""
			(at 238.76 217.17 0)
			(effects
				(font
					(size 1.27 1.27)
				)
				(hide yes)
			)
		)
		(property "Author" "Antmicro"
			(at 247.65 224.79 0)
			(effects
				(font
					(size 1.27 1.27)
					(thickness 0.15)
				)
				(justify left bottom)
				(hide yes)
			)
		)
		(property "License" "Apache-2.0"
			(at 247.65 227.33 0)
			(effects
				(font
					(size 1.27 1.27)
					(thickness 0.15)
				)
				(justify left bottom)
				(hide yes)
			)
		)
		(pin "1"
		)
		(instances
			(project "jetson-agx-thor-baseboard"
				(path ""
					(reference "#PWR075")
					(unit 1)
				)
			)
		)
	)
	(symbol
		(lib_id "antmicroResistors0402:R_470R_0402")
		(at 345.44 195.58 90)
		(unit 1)
		(exclude_from_sim no)
		(in_bom yes)
		(on_board yes)
		(dnp no)
		(fields_autoplaced yes)
		(property "Reference" "R257"
			(at 347.98 191.77 90)
			(effects
				(font
					(size 1.27 1.27)
					(thickness 0.15)
				)
				(justify right)
			)
		)
		(property "Value" "R_470R_0402"
			(at 358.14 175.26 0)
			(effects
				(font
					(size 1.27 1.27)
					(thickness 0.15)
				)
				(justify left bottom)
				(hide yes)
			)
		)
		(property "Footprint" "antmicro-footprints:R_0402_1005Metric"
			(at 360.68 175.26 0)
			(effects
				(font
					(size 1.27 1.27)
					(thickness 0.15)
				)
				(justify left bottom)
				(hide yes)
			)
		)
		(property "Datasheet" "https://www.bourns.com/docs/product-datasheets/cr.pdf"
			(at 363.22 175.26 0)
			(effects
				(font
					(size 1.27 1.27)
					(thickness 0.15)
				)
				(justify left bottom)
				(hide yes)
			)
		)
		(property "Description" "SMD Chip Resistor, 470 ohm, ± 1%, 62.5 mW, 0402 [1005 Metric], Thick Film, General Purpose"
			(at 345.44 195.58 0)
			(effects
				(font
					(size 1.27 1.27)
				)
				(hide yes)
			)
		)
		(property "MPN" "CR0402-FX-4700GLF"
			(at 365.76 175.26 0)
			(effects
				(font
					(size 1.27 1.27)
					(thickness 0.15)
				)
				(justify left bottom)
				(hide yes)
			)
		)
		(property "Manufacturer" "Bourns"
			(at 368.3 175.26 0)
			(effects
				(font
					(size 1.27 1.27)
					(thickness 0.15)
				)
				(justify left bottom)
				(hide yes)
			)
		)
		(property "License" "Apache-2.0"
			(at 370.84 175.26 0)
			(effects
				(font
					(size 1.27 1.27)
					(thickness 0.15)
				)
				(justify left bottom)
				(hide yes)
			)
		)
		(property "Author" "Antmicro"
			(at 373.38 175.26 0)
			(effects
				(font
					(size 1.27 1.27)
					(thickness 0.15)
				)
				(justify left bottom)
				(hide yes)
			)
		)
		(property "Val" "470R"
			(at 347.98 194.31 90)
			(effects
				(font
					(size 1.27 1.27)
					(thickness 0.15)
				)
				(justify right)
			)
		)
		(property "Tolerance" "1%"
			(at 355.6 175.26 0)
			(effects
				(font
					(size 1.27 1.27)
				)
				(justify left bottom)
				(hide yes)
			)
		)
		(pin "2"
		)
		(pin "1"
		)
		(instances
			(project "jetson-agx-thor-baseboard"
				(path ""
					(reference "R257")
					(unit 1)
				)
			)
		)
	)
	(symbol
		(lib_id "antmicroTestPoints:TP_0.75mm_SMD")
		(at 335.28 210.82 0)
		(mirror y)
		(unit 1)
		(exclude_from_sim no)
		(in_bom no)
		(on_board yes)
		(dnp no)
		(property "Reference" "TP42"
			(at 334.01 207.772 0)
			(effects
				(font
					(size 1.27 1.27)
				)
				(justify left)
			)
		)
		(property "Value" "TP_0.75mm_SMD"
			(at 325.12 214.63 0)
			(effects
				(font
					(size 1.27 1.27)
					(thickness 0.15)
				)
				(justify left bottom)
				(hide yes)
			)
		)
		(property "Footprint" "antmicro-footprints:TP_SMD_0.75mm"
			(at 325.12 217.17 0)
			(effects
				(font
					(size 1.27 1.27)
					(thickness 0.15)
				)
				(justify left bottom)
				(hide yes)
			)
		)
		(property "Datasheet" ""
			(at 317.5 223.52 0)
			(effects
				(font
					(size 1.27 1.27)
					(thickness 0.15)
				)
				(justify left bottom)
				(hide yes)
			)
		)
		(property "Description" "SMT test point"
			(at 335.28 210.82 0)
			(effects
				(font
					(size 1.27 1.27)
				)
				(hide yes)
			)
		)
		(property "MPN" ""
			(at 324.485 222.25 0)
			(effects
				(font
					(size 1.27 1.27)
					(thickness 0.15)
				)
				(justify left bottom)
				(hide yes)
			)
		)
		(property "Manufacturer" ""
			(at 324.485 217.17 0)
			(effects
				(font
					(size 1.27 1.27)
					(thickness 0.15)
				)
				(justify left bottom)
				(hide yes)
			)
		)
		(property "Author" "Antmicro"
			(at 325.12 219.71 0)
			(effects
				(font
					(size 1.27 1.27)
					(thickness 0.15)
				)
				(justify left bottom)
				(hide yes)
			)
		)
		(property "License" "Apache-2.0"
			(at 325.12 222.25 0)
			(effects
				(font
					(size 1.27 1.27)
					(thickness 0.15)
				)
				(justify left bottom)
				(hide yes)
			)
		)
		(pin "1"
		)
		(instances
			(project "jetson-agx-thor-baseboard"
				(path ""
					(reference "TP42")
					(unit 1)
				)
			)
		)
	)
	(symbol
		(lib_id "antmicropower:GND")
		(at 110.49 88.9 0)
		(unit 1)
		(exclude_from_sim no)
		(in_bom yes)
		(on_board yes)
		(dnp no)
		(property "Reference" "#PWR0152"
			(at 110.49 95.25 0)
			(effects
				(font
					(size 1.27 1.27)
				)
				(justify left bottom)
				(hide yes)
			)
		)
		(property "Value" "GND"
			(at 110.49 92.71 0)
			(effects
				(font
					(size 1.27 1.27)
					(thickness 0.15)
				)
			)
		)
		(property "Footprint" ""
			(at 119.38 96.52 0)
			(effects
				(font
					(size 1.27 1.27)
					(thickness 0.15)
				)
				(justify left bottom)
				(hide yes)
			)
		)
		(property "Datasheet" ""
			(at 119.38 101.6 0)
			(effects
				(font
					(size 1.27 1.27)
					(thickness 0.15)
				)
				(justify left bottom)
				(hide yes)
			)
		)
		(property "Description" ""
			(at 110.49 88.9 0)
			(effects
				(font
					(size 1.27 1.27)
				)
				(hide yes)
			)
		)
		(property "Author" "Antmicro"
			(at 119.38 96.52 0)
			(effects
				(font
					(size 1.27 1.27)
					(thickness 0.15)
				)
				(justify left bottom)
				(hide yes)
			)
		)
		(property "License" "Apache-2.0"
			(at 119.38 99.06 0)
			(effects
				(font
					(size 1.27 1.27)
					(thickness 0.15)
				)
				(justify left bottom)
				(hide yes)
			)
		)
		(pin "1"
		)
		(instances
			(project "jetson-agx-thor-baseboard"
				(path ""
					(reference "#PWR0152")
					(unit 1)
				)
			)
		)
	)
	(symbol
		(lib_id "antmicropower:PWR_FLAG")
		(at 276.86 120.65 0)
		(unit 1)
		(exclude_from_sim no)
		(in_bom yes)
		(on_board yes)
		(dnp no)
		(property "Reference" "#FLG013"
			(at 276.86 118.745 0)
			(effects
				(font
					(size 1.27 1.27)
				)
				(hide yes)
			)
		)
		(property "Value" "PWR_FLAG"
			(at 276.86 116.84 0)
			(effects
				(font
					(size 1.27 1.27)
				)
			)
		)
		(property "Footprint" ""
			(at 276.86 120.65 0)
			(effects
				(font
					(size 1.27 1.27)
				)
				(hide yes)
			)
		)
		(property "Datasheet" ""
			(at 276.86 120.65 0)
			(effects
				(font
					(size 1.27 1.27)
				)
				(hide yes)
			)
		)
		(property "Description" ""
			(at 276.86 120.65 0)
			(effects
				(font
					(size 1.27 1.27)
				)
				(hide yes)
			)
		)
		(pin "1"
		)
		(instances
			(project "jetson-agx-thor-baseboard"
				(path ""
					(reference "#FLG013")
					(unit 1)
				)
			)
		)
	)
	(symbol
		(lib_id "antmicropower:GND")
		(at 290.83 217.17 0)
		(unit 1)
		(exclude_from_sim no)
		(in_bom yes)
		(on_board yes)
		(dnp no)
		(property "Reference" "#PWR0511"
			(at 290.83 223.52 0)
			(effects
				(font
					(size 1.27 1.27)
				)
				(justify left bottom)
				(hide yes)
			)
		)
		(property "Value" "GND"
			(at 290.83 220.98 0)
			(effects
				(font
					(size 1.27 1.27)
					(thickness 0.15)
				)
			)
		)
		(property "Footprint" ""
			(at 299.72 224.79 0)
			(effects
				(font
					(size 1.27 1.27)
					(thickness 0.15)
				)
				(justify left bottom)
				(hide yes)
			)
		)
		(property "Datasheet" ""
			(at 299.72 229.87 0)
			(effects
				(font
					(size 1.27 1.27)
					(thickness 0.15)
				)
				(justify left bottom)
				(hide yes)
			)
		)
		(property "Description" ""
			(at 290.83 217.17 0)
			(effects
				(font
					(size 1.27 1.27)
				)
				(hide yes)
			)
		)
		(property "Author" "Antmicro"
			(at 299.72 224.79 0)
			(effects
				(font
					(size 1.27 1.27)
					(thickness 0.15)
				)
				(justify left bottom)
				(hide yes)
			)
		)
		(property "License" "Apache-2.0"
			(at 299.72 227.33 0)
			(effects
				(font
					(size 1.27 1.27)
					(thickness 0.15)
				)
				(justify left bottom)
				(hide yes)
			)
		)
		(pin "1"
		)
		(instances
			(project "jetson-agx-thor-baseboard"
				(path ""
					(reference "#PWR0511")
					(unit 1)
				)
			)
		)
	)
	(symbol
		(lib_id "antmicroCapacitors0402:C_100n_0402")
		(at 276.86 142.24 90)
		(unit 1)
		(exclude_from_sim no)
		(in_bom no)
		(on_board yes)
		(dnp yes)
		(fields_autoplaced yes)
		(property "Reference" "C240"
			(at 274.32 138.4236 90)
			(effects
				(font
					(size 1.27 1.27)
					(thickness 0.15)
				)
				(justify left)
			)
		)
		(property "Value" "C_100n_0402"
			(at 299.72 127 0)
			(effects
				(font
					(size 1.27 1.27)
					(thickness 0.15)
				)
				(justify left bottom)
				(hide yes)
			)
		)
		(property "Footprint" "antmicro-footprints:C_0402_1005Metric"
			(at 302.26 127 0)
			(effects
				(font
					(size 1.27 1.27)
					(thickness 0.15)
				)
				(justify left bottom)
				(hide yes)
			)
		)
		(property "Datasheet" "https://www.murata.com/products/productdetail?partno=GRM155R61H104KE14%23"
			(at 304.8 127 0)
			(effects
				(font
					(size 1.27 1.27)
					(thickness 0.15)
				)
				(justify left bottom)
				(hide yes)
			)
		)
		(property "Description" "SMD Multilayer Ceramic Capacitor, 0.1 µF, 50 V, 0402 [1005 Metric], ± 10%, X5R, GRM Series"
			(at 276.86 142.24 0)
			(effects
				(font
					(size 1.27 1.27)
				)
				(hide yes)
			)
		)
		(property "MPN" "GRM155R61H104KE14D"
			(at 307.34 127 0)
			(effects
				(font
					(size 1.27 1.27)
					(thickness 0.15)
				)
				(justify left bottom)
				(hide yes)
			)
		)
		(property "Val" "100n"
			(at 274.32 140.9636 90)
			(effects
				(font
					(size 1.27 1.27)
					(thickness 0.15)
				)
				(justify left)
			)
		)
		(property "Voltage" "50V"
			(at 287.02 127 0)
			(effects
				(font
					(size 1.27 1.27)
					(thickness 0.15)
				)
				(justify left bottom)
				(hide yes)
			)
		)
		(property "Dielectric" "X5R"
			(at 289.56 127 0)
			(effects
				(font
					(size 1.27 1.27)
					(thickness 0.15)
				)
				(justify left bottom)
				(hide yes)
			)
		)
		(property "Manufacturer" "Murata"
			(at 292.1 127 0)
			(effects
				(font
					(size 1.27 1.27)
					(thickness 0.15)
				)
				(justify left bottom)
				(hide yes)
			)
		)
		(property "License" "Apache-2.0"
			(at 294.64 127 0)
			(effects
				(font
					(size 1.27 1.27)
					(thickness 0.15)
				)
				(justify left bottom)
				(hide yes)
			)
		)
		(property "Author" "Antmicro"
			(at 297.18 127 0)
			(effects
				(font
					(size 1.27 1.27)
					(thickness 0.15)
				)
				(justify left bottom)
				(hide yes)
			)
		)
		(pin "1"
		)
		(pin "2"
		)
		(instances
			(project "jetson-agx-thor-baseboard"
				(path ""
					(reference "C240")
					(unit 1)
				)
			)
		)
	)
	(symbol
		(lib_id "antmicroResistors0402:R_11k8_0402")
		(at 280.67 48.26 90)
		(unit 1)
		(exclude_from_sim no)
		(in_bom yes)
		(on_board yes)
		(dnp no)
		(property "Reference" "R411"
			(at 281.94 44.45 90)
			(effects
				(font
					(size 1.27 1.27)
					(thickness 0.15)
				)
				(justify right)
			)
		)
		(property "Value" "R_11k8_0402"
			(at 293.37 27.94 0)
			(effects
				(font
					(size 1.27 1.27)
					(thickness 0.15)
				)
				(justify left bottom)
				(hide yes)
			)
		)
		(property "Footprint" "antmicro-footprints:R_0402_1005Metric"
			(at 295.91 27.94 0)
			(effects
				(font
					(size 1.27 1.27)
					(thickness 0.15)
				)
				(justify left bottom)
				(hide yes)
			)
		)
		(property "Datasheet" "https://www.bourns.com/docs/product-datasheets/cr.pdf"
			(at 298.45 27.94 0)
			(effects
				(font
					(size 1.27 1.27)
					(thickness 0.15)
				)
				(justify left bottom)
				(hide yes)
			)
		)
		(property "Description" "SMD Chip Resistor, 11.8 kohm, ± 1%, 100 mW, 0402 [1005 Metric], Thick Film, Precision"
			(at 311.15 27.94 0)
			(effects
				(font
					(size 1.27 1.27)
				)
				(justify left bottom)
				(hide yes)
			)
		)
		(property "MPN" "CR0402-FX-1182GLF"
			(at 300.99 27.94 0)
			(effects
				(font
					(size 1.27 1.27)
					(thickness 0.15)
				)
				(justify left bottom)
				(hide yes)
			)
		)
		(property "Manufacturer" "Bourns"
			(at 303.53 27.94 0)
			(effects
				(font
					(size 1.27 1.27)
					(thickness 0.15)
				)
				(justify left bottom)
				(hide yes)
			)
		)
		(property "License" "Apache-2.0"
			(at 306.07 27.94 0)
			(effects
				(font
					(size 1.27 1.27)
					(thickness 0.15)
				)
				(justify left bottom)
				(hide yes)
			)
		)
		(property "Author" "Antmicro"
			(at 308.61 27.94 0)
			(effects
				(font
					(size 1.27 1.27)
					(thickness 0.15)
				)
				(justify left bottom)
				(hide yes)
			)
		)
		(property "Val" "11k8"
			(at 281.94 46.99 90)
			(effects
				(font
					(size 1.27 1.27)
					(thickness 0.15)
				)
				(justify right)
			)
		)
		(property "Tolerance" "1%"
			(at 290.83 27.94 0)
			(effects
				(font
					(size 1.27 1.27)
				)
				(justify left bottom)
				(hide yes)
			)
		)
		(pin "1"
		)
		(pin "2"
		)
		(instances
			(project ""
				(path ""
					(reference "R411")
					(unit 1)
				)
			)
		)
	)
	(symbol
		(lib_id "antmicropower:+5V")
		(at 208.28 181.61 0)
		(unit 1)
		(exclude_from_sim no)
		(in_bom yes)
		(on_board yes)
		(dnp no)
		(property "Reference" "#PWR0178"
			(at 208.28 185.42 0)
			(effects
				(font
					(size 1.27 1.27)
				)
				(justify left bottom)
				(hide yes)
			)
		)
		(property "Value" "+12V"
			(at 208.28 177.292 0)
			(effects
				(font
					(size 1.27 1.27)
					(thickness 0.15)
				)
			)
		)
		(property "Footprint" ""
			(at 223.52 189.23 0)
			(effects
				(font
					(size 1.27 1.27)
					(thickness 0.15)
				)
				(justify left bottom)
				(hide yes)
			)
		)
		(property "Datasheet" ""
			(at 223.52 191.77 0)
			(effects
				(font
					(size 1.27 1.27)
					(thickness 0.15)
				)
				(justify left bottom)
				(hide yes)
			)
		)
		(property "Description" ""
			(at 208.28 181.61 0)
			(effects
				(font
					(size 1.27 1.27)
				)
				(hide yes)
			)
		)
		(property "Author" "Antmicro"
			(at 223.52 189.23 0)
			(effects
				(font
					(size 1.27 1.27)
					(thickness 0.15)
				)
				(justify left bottom)
				(hide yes)
			)
		)
		(property "License" "Apache-2.0"
			(at 223.52 191.77 0)
			(effects
				(font
					(size 1.27 1.27)
					(thickness 0.15)
				)
				(justify left bottom)
				(hide yes)
			)
		)
		(pin "1"
		)
		(instances
			(project "jetson-agx-thor-baseboard"
				(path ""
					(reference "#PWR0178")
					(unit 1)
				)
			)
		)
	)
	(symbol
		(lib_id "antmicropower:VCC")
		(at 273.05 34.29 0)
		(unit 1)
		(exclude_from_sim no)
		(in_bom yes)
		(on_board yes)
		(dnp no)
		(property "Reference" "#PWR056"
			(at 273.05 38.1 0)
			(effects
				(font
					(size 1.27 1.27)
				)
				(justify left bottom)
				(hide yes)
			)
		)
		(property "Value" "VCC_NO_OVP"
			(at 267.335 30.48 0)
			(effects
				(font
					(size 1.27 1.27)
				)
				(justify left)
			)
		)
		(property "Footprint" ""
			(at 273.05 34.29 0)
			(effects
				(font
					(size 1.27 1.27)
				)
				(hide yes)
			)
		)
		(property "Datasheet" ""
			(at 273.05 34.29 0)
			(effects
				(font
					(size 1.27 1.27)
				)
				(hide yes)
			)
		)
		(property "Description" ""
			(at 273.05 34.29 0)
			(effects
				(font
					(size 1.27 1.27)
				)
				(hide yes)
			)
		)
		(pin "1"
		)
		(instances
			(project "jetson-agx-thor-baseboard"
				(path ""
					(reference "#PWR056")
					(unit 1)
				)
			)
		)
	)
	(symbol
		(lib_id "antmicroTestPoints:TP_0.75mm_SMD")
		(at 196.85 187.96 180)
		(unit 1)
		(exclude_from_sim no)
		(in_bom no)
		(on_board yes)
		(dnp no)
		(property "Reference" "TP127"
			(at 186.69 187.96 0)
			(effects
				(font
					(size 1.27 1.27)
				)
				(justify right)
			)
		)
		(property "Value" "TP_0.75mm_SMD"
			(at 186.69 184.15 0)
			(effects
				(font
					(size 1.27 1.27)
					(thickness 0.15)
				)
				(justify left bottom)
				(hide yes)
			)
		)
		(property "Footprint" "antmicro-footprints:TP_SMD_0.75mm"
			(at 186.69 181.61 0)
			(effects
				(font
					(size 1.27 1.27)
					(thickness 0.15)
				)
				(justify left bottom)
				(hide yes)
			)
		)
		(property "Datasheet" ""
			(at 179.07 175.26 0)
			(effects
				(font
					(size 1.27 1.27)
					(thickness 0.15)
				)
				(justify left bottom)
				(hide yes)
			)
		)
		(property "Description" "SMT test point"
			(at 196.85 187.96 0)
			(effects
				(font
					(size 1.27 1.27)
				)
				(hide yes)
			)
		)
		(property "MPN" ""
			(at 186.055 176.53 0)
			(effects
				(font
					(size 1.27 1.27)
					(thickness 0.15)
				)
				(justify left bottom)
				(hide yes)
			)
		)
		(property "Manufacturer" ""
			(at 186.055 181.61 0)
			(effects
				(font
					(size 1.27 1.27)
					(thickness 0.15)
				)
				(justify left bottom)
				(hide yes)
			)
		)
		(property "Author" "Antmicro"
			(at 186.69 179.07 0)
			(effects
				(font
					(size 1.27 1.27)
					(thickness 0.15)
				)
				(justify left bottom)
				(hide yes)
			)
		)
		(property "License" "Apache-2.0"
			(at 186.69 176.53 0)
			(effects
				(font
					(size 1.27 1.27)
					(thickness 0.15)
				)
				(justify left bottom)
				(hide yes)
			)
		)
		(pin "1"
		)
		(instances
			(project "jetson-agx-thor-baseboard"
				(path ""
					(reference "TP127")
					(unit 1)
				)
			)
		)
	)
)
